FILE_TYPE = MACRO_DRAWING;
SET COLOR_WIRE YELLOW;
SET COLOR_PROP ORANGE;
SET COLOR_DOT WHITE;
SET COLOR_ARC YELLOW;
SET COLOR_BODY GREEN;
SET COLOR_NOTE PURPLE;
SET PROP_DISPLAY VALUE;
SET PAGE_NUMBER P171;
FORCEADD UNIVERSAL_GND..1
(-1300 -1025);
FORCEPROP 3 LASTPIN (-1300 -975) SIG_NAME GND\g
J 0
(-1290 -965);
DISPLAY 0.659574 (-1290 -965);
PAINT MONO (-1290 -965);
DISPLAY INVISIBLE (-1290 -965);
FORCEPROP 1 LAST PATH I1
J 0
(-1225 -1025);
DISPLAY 0.872340 (-1225 -1025);
PAINT AQUA (-1225 -1025);
DISPLAY INVISIBLE (-1225 -1025);
FORCEPROP 1 LAST HDL_POWER GND
J 1
(-1275 -1100);
DISPLAY 0.872340 (-1275 -1100);
PAINT GREEN (-1275 -1100);
DISPLAY INVISIBLE (-1275 -1100);
FORCEPROP 2 LAST CDS_LIB logical_power
J 0
(-1300 -1025);
DISPLAY INVISIBLE (-1300 -1025);
FORCEADD Q_CAP..1
(1125 -775);
FORCEPROP 1 LAST PART_NUMBER CH01806JB07
J 0
(1175 -925);
DISPLAY 0.787234 (1175 -925);
DISPLAY INVISIBLE (1175 -925);
FORCEPROP 1 LAST VALUE 18PF
J 0
(1175 -725);
DISPLAY 0.787234 (1175 -725);
FORCEPROP 1 LAST VOLTAGE 50V
J 0
(1175 -775);
DISPLAY 0.787234 (1175 -775);
FORCEPROP 1 LAST TOLERANCE 5%
J 0
(1175 -825);
DISPLAY 0.787234 (1175 -825);
FORCEPROP 1 LAST PACK_TYPE 0402
J 0
(1175 -975);
DISPLAY 0.787234 (1175 -975);
FORCEPROP 1 LAST MATERIAL C0G
J 0
(1175 -875);
DISPLAY 0.787234 (1175 -875);
FORCEPROP 1 LAST $LOCATION C1507
J 0
(1175 -675);
DISPLAY 0.787234 (1175 -675);
FORCEPROP 1 LAST PATH I10
J 0
(1175 -625);
DISPLAY 0.978723 (1175 -625);
PAINT WHITE (1175 -625);
DISPLAY INVISIBLE (1175 -625);
FORCEPROP 2 LAST CDS_LIB pure_quanta
J 0
(1125 -775);
PAINT MONO (1125 -775);
DISPLAY INVISIBLE (1125 -775);
FORCEPROP 2 LAST CDS_LOCATION C1507
J 0
(1175 -575);
DISPLAY 1.021277 (1175 -575);
DISPLAY INVISIBLE (1175 -575);
FORCEPROP 2 LAST $SEC 1
J 0
(1175 -575);
DISPLAY 0.680851 (1175 -575);
PAINT MONO (1175 -575);
DISPLAY INVISIBLE (1175 -575);
FORCEPROP 2 LAST CDS_SEC 1
J 0
(1175 -575);
DISPLAY 0.680851 (1175 -575);
DISPLAY INVISIBLE (1175 -575);
FORCEPROP 1 LASTPIN (1125 -675) $PN 1
J 0
(1135 -695);
DISPLAY 0.787234 (1135 -695);
DISPLAY INVISIBLE (1135 -695);
FORCEPROP 1 LASTPIN (1125 -875) $PN 2
J 0
(1135 -895);
DISPLAY 0.787234 (1135 -895);
DISPLAY INVISIBLE (1135 -895);
FORCEADD OFFPAGE..2
(3875 2700);
FORCEPROP 2 LAST $XR0 179 
J 0
(4064 2700);
DISPLAY 0.638298 (4064 2700);
PAINT MONO (4064 2700);
FORCEPROP 2 LAST CDS_LIB standard
J 0
(3875 2700);
PAINT MONO (3875 2700);
DISPLAY INVISIBLE (3875 2700);
FORCEPROP 2 LAST PATH I100
J 0
(4075 2750);
DISPLAY 1.021277 (4075 2750);
DISPLAY INVISIBLE (4075 2750);
FORCEPROP 1 LAST COMMENT_BODY TRUE
J 0
(3830 2605);
DISPLAY 0.872340 (3830 2605);
PAINT GREEN (3830 2605);
DISPLAY INVISIBLE (3830 2605);
FORCEPROP 1 LAST OFFPAGE TRUE
J 0
(4200 2575);
DISPLAY 0.872340 (4200 2575);
DISPLAY INVISIBLE (4200 2575);
FORCEADD Q_RES..1
(-325 675);
FORCEPROP 1 LAST PART_NUMBER CS00002JB13
J 0
(-400 725);
DISPLAY 0.319149 (-400 725);
DISPLAY INVISIBLE (-400 725);
FORCEPROP 1 LAST MATERIAL EMPTY
J 0
(-100 675);
DISPLAY 0.404255 (-100 675);
PAINT RED (-100 675);
FORCEPROP 1 LAST WATTAGE 1/16W
J 2
(-225 750);
DISPLAY 0.319149 (-225 750);
FORCEPROP 1 LAST VALUE 0
J 2
(-175 675);
DISPLAY 0.404255 (-175 675);
FORCEPROP 1 LAST PACK_TYPE 0402LF
J 0
(-400 750);
DISPLAY 0.319149 (-400 750);
FORCEPROP 1 LAST TOLERANCE 5%
J 0
(-150 675);
DISPLAY 0.404255 (-150 675);
FORCEPROP 1 LAST $LOCATION R1720
J 0
(-525 675);
DISPLAY 0.510638 (-525 675);
FORCEPROP 1 LASTPIN (-425 675) $PN 1
J 0
(-413 687);
DISPLAY 0.787234 (-413 687);
FORCEPROP 1 LASTPIN (-225 675) $PN 2
J 0
(-263 687);
DISPLAY 0.787234 (-263 687);
FORCEPROP 1 LAST PATH I103
J 0
(-375 825);
DISPLAY 0.978723 (-375 825);
PAINT WHITE (-375 825);
DISPLAY INVISIBLE (-375 825);
FORCEPROP 2 LAST CDS_LIB pure_quanta
J 0
(-325 675);
PAINT MONO (-325 675);
DISPLAY INVISIBLE (-325 675);
FORCEPROP 2 LAST CDS_LOCATION R1720
J 0
(-375 875);
DISPLAY 1.021277 (-375 875);
DISPLAY INVISIBLE (-375 875);
FORCEPROP 2 LAST $SEC 1
J 0
(-375 875);
DISPLAY 0.680851 (-375 875);
PAINT MONO (-375 875);
DISPLAY INVISIBLE (-375 875);
FORCEPROP 2 LAST CDS_SEC 1
J 0
(-375 875);
DISPLAY 1.021277 (-375 875);
DISPLAY INVISIBLE (-375 875);
FORCEADD Q_RES..1
(2200 225);
FORCEPROP 1 LAST PART_NUMBER CS00002JB13
J 0
(2125 275);
DISPLAY 0.319149 (2125 275);
DISPLAY INVISIBLE (2125 275);
FORCEPROP 1 LAST PACK_TYPE 0402LF
J 0
(2125 300);
DISPLAY 0.319149 (2125 300);
FORCEPROP 1 LAST WATTAGE 1/16W
J 2
(2300 300);
DISPLAY 0.319149 (2300 300);
FORCEPROP 1 LAST MATERIAL CHIP
J 0
(2425 225);
DISPLAY 0.404255 (2425 225);
FORCEPROP 1 LAST TOLERANCE 5%
J 0
(2375 225);
DISPLAY 0.404255 (2375 225);
FORCEPROP 1 LAST VALUE 0
J 2
(2350 225);
DISPLAY 0.404255 (2350 225);
FORCEPROP 1 LAST $LOCATION R1721
J 0
(2000 225);
DISPLAY 0.510638 (2000 225);
FORCEPROP 1 LASTPIN (2100 225) $PN 1
J 0
(2112 237);
DISPLAY 0.787234 (2112 237);
FORCEPROP 1 LASTPIN (2300 225) $PN 2
J 0
(2262 237);
DISPLAY 0.787234 (2262 237);
FORCEPROP 1 LAST PATH I104
J 0
(2150 375);
DISPLAY 0.978723 (2150 375);
PAINT WHITE (2150 375);
DISPLAY INVISIBLE (2150 375);
FORCEPROP 2 LAST CDS_LIB pure_quanta
J 0
(2200 225);
PAINT MONO (2200 225);
DISPLAY INVISIBLE (2200 225);
FORCEPROP 2 LAST CDS_LOCATION R1721
J 0
(2150 425);
DISPLAY 1.021277 (2150 425);
DISPLAY INVISIBLE (2150 425);
FORCEPROP 2 LAST $SEC 1
J 0
(2150 425);
DISPLAY 0.680851 (2150 425);
PAINT MONO (2150 425);
DISPLAY INVISIBLE (2150 425);
FORCEPROP 2 LAST CDS_SEC 1
J 0
(2150 425);
DISPLAY 1.021277 (2150 425);
DISPLAY INVISIBLE (2150 425);
FORCEADD OFFPAGE..2
(3875 2850);
FORCEPROP 2 LAST $XR0 179 
J 0
(4064 2850);
DISPLAY 0.638298 (4064 2850);
PAINT MONO (4064 2850);
FORCEPROP 1 LAST OFFPAGE TRUE
J 0
(4200 2725);
DISPLAY 0.872340 (4200 2725);
DISPLAY INVISIBLE (4200 2725);
FORCEPROP 1 LAST COMMENT_BODY TRUE
J 0
(3830 2755);
DISPLAY 0.872340 (3830 2755);
PAINT GREEN (3830 2755);
DISPLAY INVISIBLE (3830 2755);
FORCEPROP 2 LAST PATH I107
J 0
(4050 2925);
DISPLAY 1.021277 (4050 2925);
DISPLAY INVISIBLE (4050 2925);
FORCEPROP 2 LAST CDS_LIB standard
J 0
(3875 2850);
DISPLAY INVISIBLE (3875 2850);
FORCEADD OFFPAGE..2
(3875 2800);
FORCEPROP 2 LAST $XR0 179 
J 0
(4064 2800);
DISPLAY 0.638298 (4064 2800);
PAINT MONO (4064 2800);
FORCEPROP 1 LAST OFFPAGE TRUE
J 0
(4200 2675);
DISPLAY 0.872340 (4200 2675);
DISPLAY INVISIBLE (4200 2675);
FORCEPROP 1 LAST COMMENT_BODY TRUE
J 0
(3830 2705);
DISPLAY 0.872340 (3830 2705);
PAINT GREEN (3830 2705);
DISPLAY INVISIBLE (3830 2705);
FORCEPROP 2 LAST PATH I108
J 0
(4050 2875);
DISPLAY 1.021277 (4050 2875);
DISPLAY INVISIBLE (4050 2875);
FORCEPROP 2 LAST CDS_LIB standard
J 0
(3875 2800);
DISPLAY INVISIBLE (3875 2800);
FORCEADD OFFPAGE..2
(3200 1675);
FORCEPROP 2 LAST $XR0 191 
J 0
(3389 1675);
DISPLAY 0.638298 (3389 1675);
PAINT MONO (3389 1675);
FORCEPROP 2 LAST PATH I109
J 0
(3400 1725);
DISPLAY 1.021277 (3400 1725);
DISPLAY INVISIBLE (3400 1725);
FORCEPROP 1 LAST COMMENT_BODY TRUE
J 0
(3155 1580);
DISPLAY 0.872340 (3155 1580);
PAINT GREEN (3155 1580);
DISPLAY INVISIBLE (3155 1580);
FORCEPROP 1 LAST OFFPAGE TRUE
J 0
(3525 1550);
DISPLAY 0.872340 (3525 1550);
DISPLAY INVISIBLE (3525 1550);
FORCEPROP 2 LAST CDS_LIB standard
J 0
(3200 1675);
DISPLAY INVISIBLE (3200 1675);
FORCEADD Q_CRYSTAL..1
(1700 -475);
FORCEPROP 1 LAST PART_NUMBER BG632768012
J 0
(1625 -340);
DISPLAY 0.723404 (1625 -340);
PAINT GREEN (1625 -340);
DISPLAY INVISIBLE (1625 -340);
FORCEPROP 2 LAST VALUE 32.768KHZ
J 0
(1625 -250);
DISPLAY 0.680851 (1625 -250);
FORCEPROP 1 LAST MATERIAL IC
J 0
(1625 -395);
DISPLAY 0.723404 (1625 -395);
PAINT GREEN (1625 -395);
FORCEPROP 2 LAST PACK_TYPE SMLF
J 0
(1625 -200);
DISPLAY 0.680851 (1625 -200);
FORCEPROP 1 LAST $LOCATION Y1
J 0
(1625 -295);
DISPLAY 0.723404 (1625 -295);
PAINT GREEN (1625 -295);
FORCEPROP 2 LASTPIN (1600 -475) $PN 1
J 2
(1590 -465);
DISPLAY 0.808511 (1590 -465);
FORCEPROP 2 LASTPIN (1800 -475) $PN 2
J 0
(1810 -465);
DISPLAY 0.808511 (1810 -465);
FORCEPROP 2 LAST SEC_TYPE SMLF
J 0
(1625 -150);
DISPLAY 0.680851 (1625 -150);
DISPLAY INVISIBLE (1625 -150);
FORCEPROP 1 LAST NEEDS_NO_SIZE TRUE
J 0
(1700 -475);
DISPLAY 0.468085 (1700 -475);
PAINT GREEN (1700 -475);
DISPLAY INVISIBLE (1700 -475);
FORCEPROP 2 LAST CDS_LIB pure_quanta
J 0
(1700 -475);
DISPLAY INVISIBLE (1700 -475);
FORCEPROP 1 LAST PATH I11
J 0
(1750 -390);
DISPLAY 0.723404 (1750 -390);
PAINT GREEN (1750 -390);
DISPLAY INVISIBLE (1750 -390);
FORCEPROP 2 LAST CDS_LOCATION Y1
J 0
(1625 -150);
DISPLAY 1.021277 (1625 -150);
DISPLAY INVISIBLE (1625 -150);
FORCEPROP 2 LAST SEC 1
J 0
(1625 -150);
DISPLAY 0.680851 (1625 -150);
PAINT MONO (1625 -150);
DISPLAY INVISIBLE (1625 -150);
FORCEADD OFFPAGE..2
(3200 1525);
FORCEPROP 2 LAST $XR0 191 
J 0
(3389 1525);
DISPLAY 0.638298 (3389 1525);
PAINT MONO (3389 1525);
FORCEPROP 2 LAST PATH I110
J 0
(3400 1575);
DISPLAY 1.021277 (3400 1575);
DISPLAY INVISIBLE (3400 1575);
FORCEPROP 1 LAST COMMENT_BODY TRUE
J 0
(3155 1430);
DISPLAY 0.872340 (3155 1430);
PAINT GREEN (3155 1430);
DISPLAY INVISIBLE (3155 1430);
FORCEPROP 1 LAST OFFPAGE TRUE
J 0
(3525 1400);
DISPLAY 0.872340 (3525 1400);
DISPLAY INVISIBLE (3525 1400);
FORCEPROP 2 LAST CDS_LIB standard
J 0
(3200 1525);
DISPLAY INVISIBLE (3200 1525);
FORCEADD OFFPAGE..2
(3200 1300);
FORCEPROP 2 LAST $XR0 190 
J 0
(3389 1300);
DISPLAY 0.638298 (3389 1300);
PAINT MONO (3389 1300);
FORCEPROP 2 LAST PATH I111
J 0
(3400 1350);
DISPLAY 1.021277 (3400 1350);
DISPLAY INVISIBLE (3400 1350);
FORCEPROP 2 LAST CDS_LIB standard
J 0
(3200 1300);
DISPLAY INVISIBLE (3200 1300);
FORCEPROP 1 LAST OFFPAGE TRUE
J 0
(3525 1175);
DISPLAY 0.872340 (3525 1175);
DISPLAY INVISIBLE (3525 1175);
FORCEPROP 1 LAST COMMENT_BODY TRUE
J 0
(3155 1205);
DISPLAY 0.872340 (3155 1205);
PAINT GREEN (3155 1205);
DISPLAY INVISIBLE (3155 1205);
FORCEADD OFFPAGE..2
(3200 1150);
FORCEPROP 2 LAST $XR0 190 
J 0
(3389 1150);
DISPLAY 0.638298 (3389 1150);
PAINT MONO (3389 1150);
FORCEPROP 2 LAST PATH I112
J 0
(3400 1200);
DISPLAY 1.021277 (3400 1200);
DISPLAY INVISIBLE (3400 1200);
FORCEPROP 2 LAST CDS_LIB standard
J 0
(3200 1150);
DISPLAY INVISIBLE (3200 1150);
FORCEPROP 1 LAST OFFPAGE TRUE
J 0
(3525 1025);
DISPLAY 0.872340 (3525 1025);
DISPLAY INVISIBLE (3525 1025);
FORCEPROP 1 LAST COMMENT_BODY TRUE
J 0
(3155 1055);
DISPLAY 0.872340 (3155 1055);
PAINT GREEN (3155 1055);
DISPLAY INVISIBLE (3155 1055);
FORCEADD OFFPAGE..1
(-75 1675);
FORCEPROP 2 LAST $XR0 179 
J 0
(-357 1675);
DISPLAY 0.638298 (-357 1675);
PAINT MONO (-357 1675);
FORCEPROP 2 LAST PATH I114
J 0
(-325 1725);
DISPLAY 1.021277 (-325 1725);
DISPLAY INVISIBLE (-325 1725);
FORCEPROP 1 LAST COMMENT_BODY TRUE
J 0
(50 1575);
DISPLAY 0.872340 (50 1575);
PAINT GREEN (50 1575);
DISPLAY INVISIBLE (50 1575);
FORCEPROP 1 LAST OFFPAGE TRUE
J 0
(250 1550);
DISPLAY 0.872340 (250 1550);
DISPLAY INVISIBLE (250 1550);
FORCEPROP 2 LAST CDS_LIB standard
J 0
(-75 1675);
DISPLAY INVISIBLE (-75 1675);
FORCEADD Q_RES..1
(1350 1300);
FORCEPROP 1 LAST PART_NUMBER CS00002JB13
J 0
(1475 1350);
DISPLAY 0.638298 (1475 1350);
DISPLAY INVISIBLE (1475 1350);
FORCEPROP 1 LAST MATERIAL CHIP
J 0
(1475 1400);
DISPLAY 0.638298 (1475 1400);
FORCEPROP 1 LAST WATTAGE 1/16W
J 2
(1825 1400);
DISPLAY 0.638298 (1825 1400);
FORCEPROP 1 LAST TOLERANCE 5%
J 0
(1650 1300);
DISPLAY 0.787234 (1650 1300);
FORCEPROP 1 LAST VALUE 0
J 2
(1625 1300);
DISPLAY 0.787234 (1625 1300);
FORCEPROP 1 LAST PACK_TYPE 0402LF
J 0
(1750 1300);
DISPLAY 0.787234 (1750 1300);
FORCEPROP 1 LAST $LOCATION R4305
J 0
(1100 1300);
DISPLAY 0.808511 (1100 1300);
FORCEPROP 1 LASTPIN (1250 1300) $PN 1
J 0
(1262 1312);
DISPLAY 0.787234 (1262 1312);
FORCEPROP 1 LASTPIN (1450 1300) $PN 2
J 0
(1412 1312);
DISPLAY 0.787234 (1412 1312);
FORCEPROP 1 LAST PATH I116
J 0
(1300 1450);
DISPLAY 0.978723 (1300 1450);
PAINT WHITE (1300 1450);
DISPLAY INVISIBLE (1300 1450);
FORCEPROP 2 LAST CDS_LIB pure_quanta
J 0
(1350 1300);
PAINT MONO (1350 1300);
DISPLAY INVISIBLE (1350 1300);
FORCEPROP 2 LAST CDS_LOCATION R4305
J 0
(1300 1500);
DISPLAY 1.021277 (1300 1500);
DISPLAY INVISIBLE (1300 1500);
FORCEPROP 2 LAST $SEC 1
J 0
(1300 1500);
DISPLAY 0.680851 (1300 1500);
PAINT MONO (1300 1500);
DISPLAY INVISIBLE (1300 1500);
FORCEPROP 2 LAST CDS_SEC 1
J 0
(1300 1500);
DISPLAY 1.021277 (1300 1500);
DISPLAY INVISIBLE (1300 1500);
FORCEADD Q_RES..1
(1350 1150);
FORCEPROP 1 LAST PART_NUMBER CS00002JB13
J 0
(1475 1200);
DISPLAY 0.638298 (1475 1200);
DISPLAY INVISIBLE (1475 1200);
FORCEPROP 1 LAST VALUE 0
J 2
(1625 1150);
DISPLAY 0.787234 (1625 1150);
FORCEPROP 1 LAST MATERIAL CHIP
J 0
(1475 1250);
DISPLAY 0.638298 (1475 1250);
FORCEPROP 1 LAST WATTAGE 1/16W
J 2
(1825 1250);
DISPLAY 0.638298 (1825 1250);
FORCEPROP 1 LAST TOLERANCE 5%
J 0
(1650 1150);
DISPLAY 0.787234 (1650 1150);
FORCEPROP 1 LAST PACK_TYPE 0402LF
J 0
(1750 1150);
DISPLAY 0.787234 (1750 1150);
FORCEPROP 1 LAST $LOCATION R4306
J 0
(1100 1150);
DISPLAY 0.808511 (1100 1150);
FORCEPROP 1 LASTPIN (1250 1150) $PN 1
J 0
(1262 1162);
DISPLAY 0.787234 (1262 1162);
FORCEPROP 1 LASTPIN (1450 1150) $PN 2
J 0
(1412 1162);
DISPLAY 0.787234 (1412 1162);
FORCEPROP 1 LAST PATH I117
J 0
(1300 1300);
DISPLAY 0.978723 (1300 1300);
PAINT WHITE (1300 1300);
DISPLAY INVISIBLE (1300 1300);
FORCEPROP 2 LAST CDS_LIB pure_quanta
J 0
(1350 1150);
PAINT MONO (1350 1150);
DISPLAY INVISIBLE (1350 1150);
FORCEPROP 2 LAST CDS_LOCATION R4306
J 0
(1300 1350);
DISPLAY 1.021277 (1300 1350);
DISPLAY INVISIBLE (1300 1350);
FORCEPROP 2 LAST $SEC 1
J 0
(1300 1350);
DISPLAY 0.680851 (1300 1350);
PAINT MONO (1300 1350);
DISPLAY INVISIBLE (1300 1350);
FORCEPROP 2 LAST CDS_SEC 1
J 0
(1300 1350);
DISPLAY 1.021277 (1300 1350);
DISPLAY INVISIBLE (1300 1350);
FORCEADD OFFPAGE..1
(-75 1525);
FORCEPROP 2 LAST $XR0 179 
J 0
(-357 1525);
DISPLAY 0.638298 (-357 1525);
PAINT MONO (-357 1525);
FORCEPROP 2 LAST PATH I118
J 0
(-325 1575);
DISPLAY 1.021277 (-325 1575);
DISPLAY INVISIBLE (-325 1575);
FORCEPROP 1 LAST COMMENT_BODY TRUE
J 0
(50 1425);
DISPLAY 0.872340 (50 1425);
PAINT GREEN (50 1425);
DISPLAY INVISIBLE (50 1425);
FORCEPROP 1 LAST OFFPAGE TRUE
J 0
(250 1400);
DISPLAY 0.872340 (250 1400);
DISPLAY INVISIBLE (250 1400);
FORCEPROP 2 LAST CDS_LIB standard
J 0
(-75 1525);
DISPLAY INVISIBLE (-75 1525);
FORCEADD OFFPAGE..1
(-75 1300);
FORCEPROP 2 LAST $XR0 179 
J 0
(-357 1300);
DISPLAY 0.638298 (-357 1300);
PAINT MONO (-357 1300);
FORCEPROP 2 LAST PATH I119
J 0
(-325 1350);
DISPLAY 1.021277 (-325 1350);
DISPLAY INVISIBLE (-325 1350);
FORCEPROP 2 LAST CDS_LIB standard
J 0
(-75 1300);
DISPLAY INVISIBLE (-75 1300);
FORCEPROP 1 LAST OFFPAGE TRUE
J 0
(250 1175);
DISPLAY 0.872340 (250 1175);
DISPLAY INVISIBLE (250 1175);
FORCEPROP 1 LAST COMMENT_BODY TRUE
J 0
(50 1200);
DISPLAY 0.872340 (50 1200);
PAINT GREEN (50 1200);
DISPLAY INVISIBLE (50 1200);
FORCEADD OFFPAGE..1
(-75 1150);
FORCEPROP 2 LAST $XR0 179 
J 0
(-357 1150);
DISPLAY 0.638298 (-357 1150);
PAINT MONO (-357 1150);
FORCEPROP 2 LAST PATH I120
J 0
(-325 1200);
DISPLAY 1.021277 (-325 1200);
DISPLAY INVISIBLE (-325 1200);
FORCEPROP 2 LAST CDS_LIB standard
J 0
(-75 1150);
DISPLAY INVISIBLE (-75 1150);
FORCEPROP 1 LAST OFFPAGE TRUE
J 0
(250 1025);
DISPLAY 0.872340 (250 1025);
DISPLAY INVISIBLE (250 1025);
FORCEPROP 1 LAST COMMENT_BODY TRUE
J 0
(50 1050);
DISPLAY 0.872340 (50 1050);
PAINT GREEN (50 1050);
DISPLAY INVISIBLE (50 1050);
FORCEADD Q_RES..1
(1350 1675);
FORCEPROP 1 LAST PART_NUMBER CS02202FB02
J 0
(1300 1775);
DISPLAY 0.510638 (1300 1775);
PAINT WHITE (1300 1775);
DISPLAY INVISIBLE (1300 1775);
FORCEPROP 1 LAST VALUE 22
J 2
(1625 1675);
DISPLAY 0.510638 (1625 1675);
FORCEPROP 1 LAST MATERIAL CHIP
J 0
(1450 1675);
DISPLAY 0.510638 (1450 1675);
FORCEPROP 1 LAST LOCATION R4303
J 0
(1075 1675);
DISPLAY 0.808511 (1075 1675);
FORCEPROP 1 LASTPIN (1250 1675) $PN 1
J 0
(1262 1687);
DISPLAY 0.787234 (1262 1687);
PAINT MONO (1262 1687);
FORCEPROP 1 LASTPIN (1450 1675) $PN 2
J 0
(1412 1687);
DISPLAY 0.787234 (1412 1687);
PAINT MONO (1412 1687);
FORCEPROP 2 LAST CDS_LIB pure_quanta
J 0
(1350 1675);
DISPLAY INVISIBLE (1350 1675);
FORCEPROP 1 LAST PATH I121
J 0
(1300 1825);
DISPLAY 0.978723 (1300 1825);
PAINT WHITE (1300 1825);
DISPLAY INVISIBLE (1300 1825);
FORCEPROP 1 LAST WATTAGE 1/16W
J 2
(1325 1525);
DISPLAY 0.510638 (1325 1525);
PAINT SKYBLUE (1325 1525);
DISPLAY INVISIBLE (1325 1525);
FORCEPROP 1 LAST TOLERANCE 1%
J 0
(1350 1575);
DISPLAY 0.510638 (1350 1575);
PAINT SKYBLUE (1350 1575);
DISPLAY INVISIBLE (1350 1575);
FORCEPROP 1 LAST PACK_TYPE 0402LF
J 0
(1600 1525);
DISPLAY 0.510638 (1600 1525);
PAINT SKYBLUE (1600 1525);
DISPLAY INVISIBLE (1600 1525);
FORCEPROP 0 LAST $SEC 1
J 0
(1425 1725);
DISPLAY 0.680851 (1425 1725);
PAINT MONO (1425 1725);
DISPLAY INVISIBLE (1425 1725);
FORCEPROP 0 LAST CDS_SEC 1
J 0
(1425 1725);
DISPLAY 1.021277 (1425 1725);
DISPLAY INVISIBLE (1425 1725);
FORCEADD Q_RES..1
(1350 1525);
FORCEPROP 1 LAST PART_NUMBER CS02202FB02
J 0
(1300 1625);
DISPLAY 0.510638 (1300 1625);
PAINT WHITE (1300 1625);
DISPLAY INVISIBLE (1300 1625);
FORCEPROP 1 LAST VALUE 22
J 2
(1625 1525);
DISPLAY 0.510638 (1625 1525);
FORCEPROP 1 LAST MATERIAL CHIP
J 0
(1450 1525);
DISPLAY 0.510638 (1450 1525);
FORCEPROP 1 LAST LOCATION R4304
J 0
(1075 1525);
DISPLAY 0.787234 (1075 1525);
FORCEPROP 1 LASTPIN (1250 1525) $PN 1
J 0
(1262 1537);
DISPLAY 0.787234 (1262 1537);
PAINT MONO (1262 1537);
FORCEPROP 1 LASTPIN (1450 1525) $PN 2
J 0
(1412 1537);
DISPLAY 0.787234 (1412 1537);
PAINT MONO (1412 1537);
FORCEPROP 1 LAST PACK_TYPE 0402LF
J 0
(1600 1375);
DISPLAY 0.510638 (1600 1375);
PAINT SKYBLUE (1600 1375);
DISPLAY INVISIBLE (1600 1375);
FORCEPROP 1 LAST TOLERANCE 1%
J 0
(1350 1425);
DISPLAY 0.510638 (1350 1425);
PAINT SKYBLUE (1350 1425);
DISPLAY INVISIBLE (1350 1425);
FORCEPROP 1 LAST WATTAGE 1/16W
J 2
(1325 1375);
DISPLAY 0.510638 (1325 1375);
PAINT SKYBLUE (1325 1375);
DISPLAY INVISIBLE (1325 1375);
FORCEPROP 1 LAST PATH I122
J 0
(1300 1675);
DISPLAY 0.978723 (1300 1675);
PAINT WHITE (1300 1675);
DISPLAY INVISIBLE (1300 1675);
FORCEPROP 2 LAST CDS_LIB pure_quanta
J 0
(1350 1525);
DISPLAY INVISIBLE (1350 1525);
FORCEPROP 0 LAST $SEC 1
J 0
(1425 1575);
DISPLAY 0.680851 (1425 1575);
PAINT MONO (1425 1575);
DISPLAY INVISIBLE (1425 1575);
FORCEPROP 0 LAST CDS_SEC 1
J 0
(1425 1575);
DISPLAY 1.021277 (1425 1575);
DISPLAY INVISIBLE (1425 1575);
FORCEADD OFFPAGE..1
R 2
(850 550);
FORCEPROP 2 LAST $XR0 179 
J 0
(1036 550);
DISPLAY 0.638298 (1036 550);
PAINT MONO (1036 550);
FORCEPROP 2 LAST PATH I14
J 0
(1050 600);
DISPLAY 1.021277 (1050 600);
DISPLAY INVISIBLE (1050 600);
FORCEPROP 1 LAST COMMENT_BODY TRUE
J 2
(725 450);
DISPLAY 0.872340 (725 450);
PAINT GREEN (725 450);
DISPLAY INVISIBLE (725 450);
FORCEPROP 1 LAST OFFPAGE TRUE
J 2
(525 425);
DISPLAY 0.872340 (525 425);
DISPLAY INVISIBLE (525 425);
FORCEPROP 2 LAST CDS_LIB standard
J 0
(850 550);
DISPLAY INVISIBLE (850 550);
FORCEADD OFFPAGE..2
(850 675);
FORCEPROP 2 LAST $XR0 179 
J 0
(1039 675);
DISPLAY 0.638298 (1039 675);
PAINT MONO (1039 675);
FORCEPROP 2 LAST PATH I15
J 0
(1050 725);
DISPLAY 1.021277 (1050 725);
DISPLAY INVISIBLE (1050 725);
FORCEPROP 1 LAST COMMENT_BODY TRUE
J 0
(805 580);
DISPLAY 0.872340 (805 580);
PAINT GREEN (805 580);
DISPLAY INVISIBLE (805 580);
FORCEPROP 1 LAST OFFPAGE TRUE
J 0
(1175 550);
DISPLAY 0.872340 (1175 550);
DISPLAY INVISIBLE (1175 550);
FORCEPROP 2 LAST CDS_LIB standard
J 0
(850 675);
DISPLAY INVISIBLE (850 675);
FORCEADD UNIVERSAL_GND..1
(2275 -1025);
FORCEPROP 3 LASTPIN (2275 -975) SIG_NAME GND\g
J 0
(2285 -965);
DISPLAY 0.659574 (2285 -965);
PAINT MONO (2285 -965);
DISPLAY INVISIBLE (2285 -965);
FORCEPROP 1 LAST HDL_POWER GND
J 1
(2300 -1100);
DISPLAY 0.872340 (2300 -1100);
PAINT GREEN (2300 -1100);
DISPLAY INVISIBLE (2300 -1100);
FORCEPROP 2 LAST CDS_LIB logical_power
J 0
(2275 -1025);
DISPLAY INVISIBLE (2275 -1025);
FORCEPROP 1 LAST PATH I16
J 0
(2350 -1025);
DISPLAY 0.872340 (2350 -1025);
PAINT AQUA (2350 -1025);
DISPLAY INVISIBLE (2350 -1025);
FORCEADD Q_CAP..1
(2275 -775);
FORCEPROP 1 LAST PART_NUMBER CH01806JB07
J 0
(2325 -925);
DISPLAY 0.787234 (2325 -925);
DISPLAY INVISIBLE (2325 -925);
FORCEPROP 1 LAST PACK_TYPE 0402
J 0
(2325 -975);
DISPLAY 0.787234 (2325 -975);
FORCEPROP 1 LAST VALUE 18PF
J 0
(2325 -725);
DISPLAY 0.787234 (2325 -725);
FORCEPROP 1 LAST VOLTAGE 50V
J 0
(2325 -775);
DISPLAY 0.787234 (2325 -775);
FORCEPROP 1 LAST MATERIAL C0G
J 0
(2325 -875);
DISPLAY 0.787234 (2325 -875);
FORCEPROP 1 LAST TOLERANCE 5%
J 0
(2325 -825);
DISPLAY 0.787234 (2325 -825);
FORCEPROP 1 LAST $LOCATION C1508
J 0
(2325 -675);
DISPLAY 0.787234 (2325 -675);
FORCEPROP 1 LAST PATH I17
J 0
(2325 -625);
DISPLAY 0.978723 (2325 -625);
PAINT WHITE (2325 -625);
DISPLAY INVISIBLE (2325 -625);
FORCEPROP 2 LAST CDS_LIB pure_quanta
J 0
(2275 -775);
PAINT MONO (2275 -775);
DISPLAY INVISIBLE (2275 -775);
FORCEPROP 2 LAST CDS_LOCATION C1508
J 0
(2325 -575);
DISPLAY 1.021277 (2325 -575);
DISPLAY INVISIBLE (2325 -575);
FORCEPROP 2 LAST $SEC 1
J 0
(2325 -575);
DISPLAY 0.680851 (2325 -575);
PAINT MONO (2325 -575);
DISPLAY INVISIBLE (2325 -575);
FORCEPROP 2 LAST CDS_SEC 1
J 0
(2325 -575);
DISPLAY 0.680851 (2325 -575);
DISPLAY INVISIBLE (2325 -575);
FORCEPROP 1 LASTPIN (2275 -675) $PN 1
J 0
(2285 -695);
DISPLAY 0.787234 (2285 -695);
DISPLAY INVISIBLE (2285 -695);
FORCEPROP 1 LASTPIN (2275 -875) $PN 2
J 0
(2285 -895);
DISPLAY 0.787234 (2285 -895);
DISPLAY INVISIBLE (2285 -895);
FORCEADD OFFPAGE..1
R 2
(3375 125);
FORCEPROP 2 LAST $XR0 179 
J 0
(3561 125);
DISPLAY 0.638298 (3561 125);
PAINT MONO (3561 125);
FORCEPROP 2 LAST PATH I18
J 0
(3575 175);
DISPLAY 1.021277 (3575 175);
DISPLAY INVISIBLE (3575 175);
FORCEPROP 1 LAST COMMENT_BODY TRUE
J 2
(3250 25);
DISPLAY 0.872340 (3250 25);
PAINT GREEN (3250 25);
DISPLAY INVISIBLE (3250 25);
FORCEPROP 1 LAST OFFPAGE TRUE
J 2
(3050 0);
DISPLAY 0.872340 (3050 0);
DISPLAY INVISIBLE (3050 0);
FORCEPROP 2 LAST CDS_LIB standard
J 0
(3375 125);
DISPLAY INVISIBLE (3375 125);
FORCEADD OFFPAGE..2
(3375 225);
FORCEPROP 2 LAST $XR0 179 
J 0
(3564 225);
DISPLAY 0.638298 (3564 225);
PAINT MONO (3564 225);
FORCEPROP 2 LAST PATH I19
J 0
(3575 275);
DISPLAY 1.021277 (3575 275);
DISPLAY INVISIBLE (3575 275);
FORCEPROP 1 LAST COMMENT_BODY TRUE
J 0
(3330 130);
DISPLAY 0.872340 (3330 130);
PAINT GREEN (3330 130);
DISPLAY INVISIBLE (3330 130);
FORCEPROP 1 LAST OFFPAGE TRUE
J 0
(3700 100);
DISPLAY 0.872340 (3700 100);
DISPLAY INVISIBLE (3700 100);
FORCEPROP 2 LAST CDS_LIB standard
J 0
(3375 225);
DISPLAY INVISIBLE (3375 225);
FORCEADD UNIVERSAL_GND..1
(-1775 3600);
FORCEPROP 3 LASTPIN (-1775 3650) SIG_NAME GND\g
J 0
(-1765 3660);
DISPLAY 0.659574 (-1765 3660);
PAINT MONO (-1765 3660);
DISPLAY INVISIBLE (-1765 3660);
FORCEPROP 1 LAST PATH I5
J 0
(-1700 3600);
DISPLAY 0.872340 (-1700 3600);
PAINT AQUA (-1700 3600);
DISPLAY INVISIBLE (-1700 3600);
FORCEPROP 1 LAST HDL_POWER GND
J 1
(-1750 3525);
DISPLAY 0.872340 (-1750 3525);
PAINT GREEN (-1750 3525);
DISPLAY INVISIBLE (-1750 3525);
FORCEPROP 2 LAST CDS_LIB logical_power
J 0
(-1775 3600);
PAINT MONO (-1775 3600);
DISPLAY INVISIBLE (-1775 3600);
FORCEADD OFFPAGE..4
R 2
(-850 3800);
FORCEPROP 2 LAST $XR0 209 
J 0
(-1132 3800);
DISPLAY 0.638298 (-1132 3800);
PAINT MONO (-1132 3800);
FORCEPROP 1 LAST COMMENT_BODY TRUE
J 2
(-825 3700);
DISPLAY 0.872340 (-825 3700);
PAINT GREEN (-825 3700);
DISPLAY INVISIBLE (-825 3700);
FORCEPROP 1 LAST OFFPAGE TRUE
J 2
(-1175 3675);
DISPLAY 0.872340 (-1175 3675);
DISPLAY INVISIBLE (-1175 3675);
FORCEPROP 2 LAST PATH I63
J 0
(-1125 3850);
DISPLAY 1.021277 (-1125 3850);
DISPLAY INVISIBLE (-1125 3850);
FORCEPROP 2 LAST CDS_LIB standard
J 0
(-850 3800);
PAINT MONO (-850 3800);
DISPLAY INVISIBLE (-850 3800);
FORCEADD OFFPAGE..4
R 2
(-850 3750);
FORCEPROP 2 LAST $XR0 209 
J 0
(-1132 3750);
DISPLAY 0.638298 (-1132 3750);
PAINT MONO (-1132 3750);
FORCEPROP 1 LAST OFFPAGE TRUE
J 2
(-1175 3625);
DISPLAY 0.872340 (-1175 3625);
DISPLAY INVISIBLE (-1175 3625);
FORCEPROP 1 LAST COMMENT_BODY TRUE
J 2
(-825 3650);
DISPLAY 0.872340 (-825 3650);
PAINT GREEN (-825 3650);
DISPLAY INVISIBLE (-825 3650);
FORCEPROP 2 LAST PATH I64
J 0
(-1125 3800);
DISPLAY 1.021277 (-1125 3800);
DISPLAY INVISIBLE (-1125 3800);
FORCEPROP 2 LAST CDS_LIB standard
J 0
(-850 3750);
PAINT MONO (-850 3750);
DISPLAY INVISIBLE (-850 3750);
FORCEADD OFFPAGE..2
R 2
(-850 3550);
FORCEPROP 2 LAST $XR0 179 
J 0
(-1105 3550);
DISPLAY 0.638298 (-1105 3550);
PAINT MONO (-1105 3550);
FORCEPROP 2 LAST PATH I66
J 0
(-1125 3600);
DISPLAY 1.021277 (-1125 3600);
DISPLAY INVISIBLE (-1125 3600);
FORCEPROP 1 LAST COMMENT_BODY TRUE
J 2
(-805 3455);
DISPLAY 0.872340 (-805 3455);
PAINT GREEN (-805 3455);
DISPLAY INVISIBLE (-805 3455);
FORCEPROP 1 LAST OFFPAGE TRUE
J 2
(-1175 3425);
DISPLAY 0.872340 (-1175 3425);
DISPLAY INVISIBLE (-1175 3425);
FORCEPROP 2 LAST CDS_LIB standard
J 0
(-850 3550);
DISPLAY INVISIBLE (-850 3550);
FORCEADD OFFPAGE..4
R 2
(-850 3450);
FORCEPROP 2 LAST $XR0 179 
J 0
(-1132 3450);
DISPLAY 0.638298 (-1132 3450);
PAINT MONO (-1132 3450);
FORCEPROP 1 LAST COMMENT_BODY TRUE
J 2
(-825 3350);
DISPLAY 0.872340 (-825 3350);
PAINT GREEN (-825 3350);
DISPLAY INVISIBLE (-825 3350);
FORCEPROP 1 LAST OFFPAGE TRUE
J 2
(-1175 3325);
DISPLAY 0.872340 (-1175 3325);
DISPLAY INVISIBLE (-1175 3325);
FORCEPROP 2 LAST PATH I67
J 0
(-1125 3500);
DISPLAY 1.021277 (-1125 3500);
DISPLAY INVISIBLE (-1125 3500);
FORCEPROP 2 LAST CDS_LIB standard
J 0
(-850 3450);
DISPLAY INVISIBLE (-850 3450);
FORCEADD OFFPAGE..5
(-850 3350);
FORCEPROP 2 LAST $XR0 179 
J 0
(-1105 3350);
DISPLAY 0.638298 (-1105 3350);
PAINT MONO (-1105 3350);
FORCEPROP 2 LAST PATH I68
J 0
(-1125 3400);
DISPLAY 1.021277 (-1125 3400);
DISPLAY INVISIBLE (-1125 3400);
FORCEPROP 1 LAST COMMENT_BODY TRUE
J 0
(-750 3275);
DISPLAY 0.872340 (-750 3275);
PAINT GREEN (-750 3275);
DISPLAY INVISIBLE (-750 3275);
FORCEPROP 1 LAST OFFPAGE TRUE
J 0
(-525 3225);
DISPLAY 0.872340 (-525 3225);
DISPLAY INVISIBLE (-525 3225);
FORCEPROP 2 LAST CDS_LIB standard
J 0
(-850 3350);
DISPLAY INVISIBLE (-850 3350);
FORCEADD Q_RES..2
(-1775 3850);
FORCEPROP 1 LAST PART_NUMBER CS06042FB03
J 0
(-1735 3725);
DISPLAY 0.638298 (-1735 3725);
DISPLAY INVISIBLE (-1735 3725);
FORCEPROP 1 LAST VALUE 60.4
J 0
(-1730 3925);
DISPLAY 0.638298 (-1730 3925);
FORCEPROP 1 LAST WATTAGE 1/16W
J 0
(-1735 3825);
DISPLAY 0.638298 (-1735 3825);
FORCEPROP 1 LAST MATERIAL CHIP
J 0
(-1735 3775);
DISPLAY 0.638298 (-1735 3775);
FORCEPROP 1 LAST PACK_TYPE 0402LF
J 0
(-1735 3675);
DISPLAY 0.638298 (-1735 3675);
FORCEPROP 1 LAST TOLERANCE 1%
J 0
(-1730 3875);
DISPLAY 0.638298 (-1730 3875);
FORCEPROP 1 LAST $LOCATION R477
J 0
(-1730 3975);
DISPLAY 0.978723 (-1730 3975);
FORCEPROP 1 LASTPIN (-1775 3950) $PN 1
J 0
(-1770 3912);
DISPLAY 0.787234 (-1770 3912);
FORCEPROP 1 LASTPIN (-1775 3750) $PN 2
J 0
(-1770 3760);
DISPLAY 0.787234 (-1770 3760);
FORCEPROP 2 LAST CDS_LIB pure_quanta
J 0
(-1775 3850);
PAINT MONO (-1775 3850);
DISPLAY INVISIBLE (-1775 3850);
FORCEPROP 1 LAST PATH I69
J 0
(-1725 4025);
DISPLAY 0.978723 (-1725 4025);
PAINT WHITE (-1725 4025);
DISPLAY INVISIBLE (-1725 4025);
FORCEPROP 2 LAST CDS_LOCATION R477
J 0
(-1725 4075);
DISPLAY 1.021277 (-1725 4075);
DISPLAY INVISIBLE (-1725 4075);
FORCEPROP 2 LAST $SEC 1
J 0
(-1725 4075);
DISPLAY 0.680851 (-1725 4075);
PAINT MONO (-1725 4075);
DISPLAY INVISIBLE (-1725 4075);
FORCEPROP 2 LAST CDS_SEC 1
J 0
(-1725 4075);
DISPLAY 1.021277 (-1725 4075);
DISPLAY INVISIBLE (-1725 4075);
FORCEADD UNIVERSAL_GND..1
(-375 -1025);
FORCEPROP 3 LASTPIN (-375 -975) SIG_NAME GND\g
J 0
(-365 -965);
DISPLAY 0.659574 (-365 -965);
PAINT MONO (-365 -965);
DISPLAY INVISIBLE (-365 -965);
FORCEPROP 1 LAST PATH I7
J 0
(-300 -1025);
DISPLAY 0.872340 (-300 -1025);
PAINT AQUA (-300 -1025);
DISPLAY INVISIBLE (-300 -1025);
FORCEPROP 1 LAST HDL_POWER GND
J 1
(-350 -1100);
DISPLAY 0.872340 (-350 -1100);
PAINT GREEN (-350 -1100);
DISPLAY INVISIBLE (-350 -1100);
FORCEPROP 2 LAST CDS_LIB logical_power
J 0
(-375 -1025);
DISPLAY INVISIBLE (-375 -1025);
FORCEADD Q_RES..1
(1675 -100);
FORCEPROP 1 LAST PART_NUMBER CS61003F901
J 0
(1600 -25);
DISPLAY 0.638298 (1600 -25);
DISPLAY INVISIBLE (1600 -25);
FORCEPROP 1 LAST MATERIAL CHIP
J 0
(1600 25);
DISPLAY 0.638298 (1600 25);
FORCEPROP 1 LAST TOLERANCE 1%
J 0
(1925 -100);
DISPLAY 0.638298 (1925 -100);
FORCEPROP 1 LAST PACK_TYPE 0603LF
J 0
(2025 -100);
DISPLAY 0.638298 (2025 -100);
FORCEPROP 1 LAST VALUE 10M
J 2
(1900 -100);
DISPLAY 0.638298 (1900 -100);
FORCEPROP 1 LAST WATTAGE 1/10W
J 2
(1975 25);
DISPLAY 0.638298 (1975 25);
FORCEPROP 1 LAST $LOCATION R120
J 0
(1475 -100);
DISPLAY 0.638298 (1475 -100);
FORCEPROP 1 LASTPIN (1575 -100) $PN 1
J 0
(1587 -88);
DISPLAY 0.787234 (1587 -88);
FORCEPROP 1 LASTPIN (1775 -100) $PN 2
J 0
(1737 -88);
DISPLAY 0.638298 (1737 -88);
FORCEPROP 2 LAST CDS_LIB pure_quanta
J 0
(1675 -100);
PAINT MONO (1675 -100);
DISPLAY INVISIBLE (1675 -100);
FORCEPROP 1 LAST PATH I74
J 0
(1625 50);
DISPLAY 0.978723 (1625 50);
PAINT WHITE (1625 50);
DISPLAY INVISIBLE (1625 50);
FORCEPROP 2 LAST CDS_LOCATION R120
J 0
(1625 100);
DISPLAY 1.021277 (1625 100);
DISPLAY INVISIBLE (1625 100);
FORCEPROP 2 LAST $SEC 1
J 0
(1625 100);
DISPLAY 0.680851 (1625 100);
PAINT MONO (1625 100);
DISPLAY INVISIBLE (1625 100);
FORCEPROP 2 LAST CDS_SEC 1
J 0
(1625 100);
DISPLAY 1.021277 (1625 100);
DISPLAY INVISIBLE (1625 100);
FORCEADD Q_XTAL_4P_13BI_24GND..1
(-825 -450);
FORCEPROP 1 LAST PART_NUMBER BG625000802
J 0
(-958 -225);
DISPLAY 0.723404 (-958 -225);
PAINT GREEN (-958 -225);
DISPLAY INVISIBLE (-958 -225);
FORCEPROP 1 LAST MATERIAL EMPTY
J 0
(-958 -271);
DISPLAY 0.723404 (-958 -271);
PAINT RED (-958 -271);
FORCEPROP 2 LAST PART_TYPE SMLF
J 0
(-950 -50);
DISPLAY 0.638298 (-950 -50);
FORCEPROP 2 LAST VALUE 25MHZ
J 0
(-950 -100);
DISPLAY 0.638298 (-950 -100);
FORCEPROP 1 LAST $LOCATION Y7
J 0
(-958 -159);
DISPLAY 0.723404 (-958 -159);
PAINT GREEN (-958 -159);
FORCEPROP 2 LASTPIN (-1100 -575) $PN 2
J 2
(-1110 -565);
DISPLAY 0.808511 (-1110 -565);
FORCEPROP 2 LASTPIN (-550 -575) $PN 4
J 0
(-540 -565);
DISPLAY 0.808511 (-540 -565);
FORCEPROP 2 LASTPIN (-1100 -375) $PN 1
J 2
(-1110 -365);
DISPLAY 0.808511 (-1110 -365);
FORCEPROP 2 LASTPIN (-550 -375) $PN 3
J 0
(-540 -365);
DISPLAY 0.808511 (-540 -365);
FORCEPROP 2 LAST CDS_LIB pure_quanta
J 0
(-825 -450);
PAINT MONO (-825 -450);
DISPLAY INVISIBLE (-825 -450);
FORCEPROP 1 LAST PATH I75
J 0
(-700 -625);
DISPLAY 0.723404 (-700 -625);
PAINT GREEN (-700 -625);
DISPLAY INVISIBLE (-700 -625);
FORCEPROP 1 LAST CDS_LMAN_SYM_OUTLINE -125,175,125,-175
J 0
(-825 -450);
DISPLAY 0.468085 (-825 -450);
PAINT GREEN (-825 -450);
DISPLAY INVISIBLE (-825 -450);
FORCEPROP 1 LAST PIN_NAMES_ROTATE True
J 0
(-825 -450);
DISPLAY 0.489362 (-825 -450);
PAINT GREEN (-825 -450);
DISPLAY INVISIBLE (-825 -450);
FORCEPROP 2 LAST CDS_LOCATION Y7
J 0
(-950 0);
DISPLAY 1.021277 (-950 0);
DISPLAY INVISIBLE (-950 0);
FORCEPROP 2 LAST $SEC 1
J 0
(-950 0);
DISPLAY 0.680851 (-950 0);
PAINT MONO (-950 0);
DISPLAY INVISIBLE (-950 0);
FORCEPROP 2 LAST CDS_SEC 1
J 0
(-950 0);
DISPLAY 1.021277 (-950 0);
DISPLAY INVISIBLE (-950 0);
FORCEADD Q_CAP..1
(-375 -775);
FORCEPROP 1 LAST PART_NUMBER CH02706JB06
J 0
(-325 -925);
DISPLAY 0.787234 (-325 -925);
DISPLAY INVISIBLE (-325 -925);
FORCEPROP 1 LAST MATERIAL EMPTY
J 0
(-325 -875);
DISPLAY 0.787234 (-325 -875);
PAINT RED (-325 -875);
FORCEPROP 1 LAST VALUE 27PF  
J 0
(-325 -725);
DISPLAY 0.787234 (-325 -725);
FORCEPROP 1 LAST VOLTAGE 50V 
J 0
(-325 -775);
DISPLAY 0.787234 (-325 -775);
FORCEPROP 1 LAST TOLERANCE 5% 
J 0
(-325 -825);
DISPLAY 0.787234 (-325 -825);
FORCEPROP 1 LAST PACK_TYPE 0402
J 0
(-325 -975);
DISPLAY 0.787234 (-325 -975);
FORCEPROP 1 LAST $LOCATION C104
J 0
(-325 -675);
DISPLAY 0.787234 (-325 -675);
FORCEPROP 2 LAST CDS_LIB pure_quanta
J 0
(-375 -775);
PAINT MONO (-375 -775);
DISPLAY INVISIBLE (-375 -775);
FORCEPROP 1 LAST PATH I76
J 0
(-325 -625);
DISPLAY 0.978723 (-325 -625);
PAINT WHITE (-325 -625);
DISPLAY INVISIBLE (-325 -625);
FORCEPROP 2 LAST CDS_LOCATION C104
J 0
(-325 -575);
DISPLAY 1.021277 (-325 -575);
DISPLAY INVISIBLE (-325 -575);
FORCEPROP 2 LAST $SEC 1
J 0
(-325 -575);
DISPLAY 0.680851 (-325 -575);
PAINT MONO (-325 -575);
DISPLAY INVISIBLE (-325 -575);
FORCEPROP 2 LAST CDS_SEC 1
J 0
(-325 -575);
DISPLAY 1.021277 (-325 -575);
DISPLAY INVISIBLE (-325 -575);
FORCEPROP 1 LASTPIN (-375 -675) $PN 1
J 0
(-365 -695);
DISPLAY 0.787234 (-365 -695);
DISPLAY INVISIBLE (-365 -695);
FORCEPROP 1 LASTPIN (-375 -875) $PN 2
J 0
(-365 -895);
DISPLAY 0.787234 (-365 -895);
DISPLAY INVISIBLE (-365 -895);
FORCEADD Q_CAP..1
R 2
(-1300 -775);
FORCEPROP 1 LAST PART_NUMBER CH02706JB06
J 2
(-1350 -925);
DISPLAY 0.787234 (-1350 -925);
DISPLAY INVISIBLE (-1350 -925);
FORCEPROP 1 LAST MATERIAL EMPTY
J 2
(-1350 -875);
DISPLAY 0.787234 (-1350 -875);
PAINT RED (-1350 -875);
FORCEPROP 1 LAST TOLERANCE 5% 
J 2
(-1350 -825);
DISPLAY 0.787234 (-1350 -825);
FORCEPROP 1 LAST VOLTAGE 50V 
J 2
(-1350 -775);
DISPLAY 0.787234 (-1350 -775);
FORCEPROP 1 LAST VALUE 27PF  
J 2
(-1350 -725);
DISPLAY 0.787234 (-1350 -725);
FORCEPROP 1 LAST PACK_TYPE 0402
J 2
(-1350 -975);
DISPLAY 0.787234 (-1350 -975);
FORCEPROP 1 LAST $LOCATION C103
J 2
(-1350 -675);
DISPLAY 0.787234 (-1350 -675);
FORCEPROP 2 LAST CDS_LIB pure_quanta
J 0
(-1300 -775);
PAINT MONO (-1300 -775);
DISPLAY INVISIBLE (-1300 -775);
FORCEPROP 1 LAST PATH I77
J 2
(-1350 -625);
DISPLAY 0.978723 (-1350 -625);
PAINT WHITE (-1350 -625);
DISPLAY INVISIBLE (-1350 -625);
FORCEPROP 2 LAST CDS_LOCATION C103
J 0
(-1350 -575);
DISPLAY 1.021277 (-1350 -575);
DISPLAY INVISIBLE (-1350 -575);
FORCEPROP 2 LAST $SEC 1
J 0
(-1350 -575);
DISPLAY 0.680851 (-1350 -575);
PAINT MONO (-1350 -575);
DISPLAY INVISIBLE (-1350 -575);
FORCEPROP 2 LAST CDS_SEC 1
J 0
(-1350 -575);
DISPLAY 1.021277 (-1350 -575);
DISPLAY INVISIBLE (-1350 -575);
FORCEPROP 1 LASTPIN (-1300 -675) $PN 1
J 2
(-1310 -695);
DISPLAY 0.787234 (-1310 -695);
DISPLAY INVISIBLE (-1310 -695);
FORCEPROP 1 LASTPIN (-1300 -875) $PN 2
J 2
(-1310 -895);
DISPLAY 0.787234 (-1310 -895);
DISPLAY INVISIBLE (-1310 -895);
FORCEADD EMMITSBURG_REV0P9..1
(1525 3175);
FORCEPROP 1 LAST PART_NUMBER AJ0QV2N0T00
J 0
(678 4439);
DISPLAY 0.723404 (678 4439);
PAINT GREEN (678 4439);
DISPLAY INVISIBLE (678 4439);
FORCEPROP 2 LAST VALUE GFNOCPU04302300-QV2N-MM#99A1WT
J 0
(700 4625);
DISPLAY 1.021277 (700 4625);
FORCEPROP 1 LAST MATERIAL IC
J 0
(678 4312);
DISPLAY 0.723404 (678 4312);
PAINT GREEN (678 4312);
FORCEPROP 2 LAST PART_TYPE SMLF
J 0
(700 4675);
DISPLAY 1.021277 (700 4675);
FORCEPROP 1 LAST $LOCATION U4
J 0
(678 4586);
DISPLAY 0.723404 (678 4586);
PAINT GREEN (678 4586);
FORCEPROP 2 LASTPIN (2525 2500) $PN A16
J 0
(2535 2510);
DISPLAY 0.808511 (2535 2510);
FORCEPROP 2 LASTPIN (2525 2600) $PN G23
J 0
(2535 2610);
DISPLAY 0.808511 (2535 2610);
FORCEPROP 2 LASTPIN (2525 2700) $PN H21
J 0
(2535 2710);
DISPLAY 0.808511 (2535 2710);
FORCEPROP 2 LASTPIN (2525 2800) $PN B17
J 0
(2535 2810);
DISPLAY 0.808511 (2535 2810);
FORCEPROP 2 LASTPIN (2525 2900) $PN B19
J 0
(2535 2910);
DISPLAY 0.808511 (2535 2910);
FORCEPROP 2 LASTPIN (2525 3000) $PN A12
J 0
(2535 3010);
DISPLAY 0.808511 (2535 3010);
FORCEPROP 2 LASTPIN (2525 3100) $PN B11
J 0
(2535 3110);
DISPLAY 0.808511 (2535 3110);
FORCEPROP 2 LASTPIN (2525 3200) $PN A14
J 0
(2535 3210);
DISPLAY 0.808511 (2535 3210);
FORCEPROP 2 LASTPIN (2525 3300) $PN F18
J 0
(2535 3310);
DISPLAY 0.808511 (2535 3310);
FORCEPROP 2 LASTPIN (2525 3400) $PN B15
J 0
(2535 3410);
DISPLAY 0.808511 (2535 3410);
FORCEPROP 2 LASTPIN (2525 3500) $PN J16
J 0
(2535 3510);
DISPLAY 0.808511 (2535 3510);
FORCEPROP 2 LASTPIN (2525 3600) $PN G16
J 0
(2535 3610);
DISPLAY 0.808511 (2535 3610);
FORCEPROP 2 LASTPIN (2525 3700) $PN A10
J 0
(2535 3710);
DISPLAY 0.808511 (2535 3710);
FORCEPROP 2 LASTPIN (2525 3800) $PN A8
J 0
(2535 3810);
DISPLAY 0.808511 (2535 3810);
FORCEPROP 2 LASTPIN (2525 3900) $PN B7
J 0
(2535 3910);
DISPLAY 0.808511 (2535 3910);
FORCEPROP 2 LASTPIN (2525 4000) $PN B5
J 0
(2535 4010);
DISPLAY 0.808511 (2535 4010);
FORCEPROP 2 LASTPIN (2525 4100) $PN A18
J 0
(2535 4110);
DISPLAY 0.808511 (2535 4110);
FORCEPROP 2 LASTPIN (2525 2550) $PN C16
J 0
(2535 2560);
DISPLAY 0.808511 (2535 2560);
FORCEPROP 2 LASTPIN (2525 2650) $PN F21
J 0
(2535 2660);
DISPLAY 0.808511 (2535 2660);
FORCEPROP 2 LASTPIN (2525 2750) $PN K21
J 0
(2535 2760);
DISPLAY 0.808511 (2535 2760);
FORCEPROP 2 LASTPIN (2525 2850) $PN D17
J 0
(2535 2860);
DISPLAY 0.808511 (2535 2860);
FORCEPROP 2 LASTPIN (2525 2950) $PN D19
J 0
(2535 2960);
DISPLAY 0.808511 (2535 2960);
FORCEPROP 2 LASTPIN (2525 3050) $PN C12
J 0
(2535 3060);
DISPLAY 0.808511 (2535 3060);
FORCEPROP 2 LASTPIN (2525 3150) $PN D11
J 0
(2535 3160);
DISPLAY 0.808511 (2535 3160);
FORCEPROP 2 LASTPIN (2525 3250) $PN C14
J 0
(2535 3260);
DISPLAY 0.808511 (2535 3260);
FORCEPROP 2 LASTPIN (2525 3350) $PN H18
J 0
(2535 3360);
DISPLAY 0.808511 (2535 3360);
FORCEPROP 2 LASTPIN (2525 3450) $PN D15
J 0
(2535 3460);
DISPLAY 0.808511 (2535 3460);
FORCEPROP 2 LASTPIN (2525 3550) $PN K18
J 0
(2535 3560);
DISPLAY 0.808511 (2535 3560);
FORCEPROP 2 LASTPIN (2525 3650) $PN H15
J 0
(2535 3660);
DISPLAY 0.808511 (2535 3660);
FORCEPROP 2 LASTPIN (2525 3750) $PN C10
J 0
(2535 3760);
DISPLAY 0.808511 (2535 3760);
FORCEPROP 2 LASTPIN (2525 3850) $PN C8
J 0
(2535 3860);
DISPLAY 0.808511 (2535 3860);
FORCEPROP 2 LASTPIN (2525 3950) $PN D7
J 0
(2535 3960);
DISPLAY 0.808511 (2535 3960);
FORCEPROP 2 LASTPIN (2525 4050) $PN C6
J 0
(2535 4060);
DISPLAY 0.808511 (2535 4060);
FORCEPROP 2 LASTPIN (2525 4150) $PN C18
J 0
(2535 4160);
DISPLAY 0.808511 (2535 4160);
FORCEPROP 2 LASTPIN (2525 2350) $PN D27
J 0
(2535 2360);
DISPLAY 0.808511 (2535 2360);
FORCEPROP 2 LASTPIN (2525 2200) $PN C28
J 0
(2535 2210);
DISPLAY 0.808511 (2535 2210);
FORCEPROP 2 LASTPIN (2525 2400) $PN B27
J 0
(2535 2410);
DISPLAY 0.808511 (2535 2410);
FORCEPROP 2 LASTPIN (2525 2250) $PN A28
J 0
(2535 2260);
DISPLAY 0.808511 (2535 2260);
FORCEPROP 2 LASTPIN (525 3900) $PN D25
J 2
(515 3910);
DISPLAY 0.808511 (515 3910);
FORCEPROP 2 LASTPIN (525 3950) $PN B25
J 2
(515 3960);
DISPLAY 0.808511 (515 3960);
FORCEPROP 2 LASTPIN (525 3750) $PN D21
J 2
(515 3760);
DISPLAY 0.808511 (515 3760);
FORCEPROP 2 LASTPIN (525 3800) $PN B21
J 2
(515 3810);
DISPLAY 0.808511 (515 3810);
FORCEPROP 2 LASTPIN (525 4100) $PN H24
J 2
(515 4110);
DISPLAY 0.808511 (515 4110);
FORCEPROP 2 LASTPIN (525 4150) $PN J23
J 2
(515 4160);
DISPLAY 0.808511 (515 4160);
FORCEPROP 2 LASTPIN (525 3250) $PN BF5
J 2
(515 3260);
DISPLAY 0.808511 (515 3260);
FORCEPROP 2 LASTPIN (525 3650) $PN BE6
J 2
(515 3660);
DISPLAY 0.808511 (515 3660);
FORCEPROP 2 LASTPIN (525 3550) $PN BF7
J 2
(515 3560);
DISPLAY 0.808511 (515 3560);
FORCEPROP 2 LASTPIN (525 4050) $PN N29
J 2
(515 4060);
DISPLAY 0.808511 (515 4060);
FORCEPROP 2 LASTPIN (525 3450) $PN B23
J 2
(515 3460);
DISPLAY 0.808511 (515 3460);
FORCEPROP 2 LASTPIN (525 3350) $PN D23
J 2
(515 3360);
DISPLAY 0.808511 (515 3360);
FORCEPROP 1 LAST PATH I78
J 0
(1525 3175);
DISPLAY 0.723404 (1525 3175);
PAINT GREEN (1525 3175);
DISPLAY INVISIBLE (1525 3175);
FORCEPROP 1 LAST NEEDS_NO_SIZE TRUE
J 0
(1525 3175);
DISPLAY 0.723404 (1525 3175);
PAINT GREEN (1525 3175);
DISPLAY INVISIBLE (1525 3175);
FORCEPROP 1 LAST CDS_LMAN_SYM_OUTLINE -850,1125,850,-1125
J 0
(1525 3175);
DISPLAY 0.468085 (1525 3175);
PAINT GREEN (1525 3175);
DISPLAY INVISIBLE (1525 3175);
FORCEPROP 2 LAST CDS_LIB pure_quanta
J 0
(1525 3175);
PAINT MONO (1525 3175);
DISPLAY INVISIBLE (1525 3175);
FORCEPROP 2 LAST CDS_LOCATION U4
J 0
(675 4475);
DISPLAY 1.021277 (675 4475);
DISPLAY INVISIBLE (675 4475);
FORCEPROP 2 LAST $SEC 1
J 0
(700 4725);
DISPLAY 0.680851 (700 4725);
PAINT MONO (700 4725);
DISPLAY INVISIBLE (700 4725);
FORCEPROP 2 LAST CDS_SEC 1
J 0
(700 4725);
DISPLAY 1.021277 (700 4725);
DISPLAY INVISIBLE (700 4725);
FORCEADD OFFPAGE..2
(3875 2400);
FORCEPROP 2 LAST $XR0 209 
J 0
(4064 2400);
DISPLAY 0.638298 (4064 2400);
PAINT MONO (4064 2400);
FORCEPROP 2 LAST PATH I83
J 0
(4050 2475);
DISPLAY 1.021277 (4050 2475);
DISPLAY INVISIBLE (4050 2475);
FORCEPROP 1 LAST OFFPAGE TRUE
J 0
(4200 2275);
DISPLAY 0.872340 (4200 2275);
DISPLAY INVISIBLE (4200 2275);
FORCEPROP 1 LAST COMMENT_BODY TRUE
J 0
(3830 2305);
DISPLAY 0.872340 (3830 2305);
PAINT GREEN (3830 2305);
DISPLAY INVISIBLE (3830 2305);
FORCEPROP 2 LAST CDS_LIB standard
J 0
(3875 2400);
DISPLAY INVISIBLE (3875 2400);
FORCEADD OFFPAGE..2
(3875 2350);
FORCEPROP 2 LAST $XR0 209 
J 0
(4064 2350);
DISPLAY 0.638298 (4064 2350);
PAINT MONO (4064 2350);
FORCEPROP 2 LAST PATH I84
J 0
(4050 2425);
DISPLAY 1.021277 (4050 2425);
DISPLAY INVISIBLE (4050 2425);
FORCEPROP 1 LAST OFFPAGE TRUE
J 0
(4200 2225);
DISPLAY 0.872340 (4200 2225);
DISPLAY INVISIBLE (4200 2225);
FORCEPROP 1 LAST COMMENT_BODY TRUE
J 0
(3830 2255);
DISPLAY 0.872340 (3830 2255);
PAINT GREEN (3830 2255);
DISPLAY INVISIBLE (3830 2255);
FORCEPROP 2 LAST CDS_LIB standard
J 0
(3875 2350);
DISPLAY INVISIBLE (3875 2350);
FORCEADD OFFPAGE..2
(3875 2250);
FORCEPROP 2 LAST $XR0 209 
J 0
(4064 2250);
DISPLAY 0.638298 (4064 2250);
PAINT MONO (4064 2250);
FORCEPROP 2 LAST PATH I85
J 0
(4050 2325);
DISPLAY 1.021277 (4050 2325);
DISPLAY INVISIBLE (4050 2325);
FORCEPROP 2 LAST CDS_LIB standard
J 0
(3875 2250);
DISPLAY INVISIBLE (3875 2250);
FORCEPROP 1 LAST COMMENT_BODY TRUE
J 0
(3830 2155);
DISPLAY 0.872340 (3830 2155);
PAINT GREEN (3830 2155);
DISPLAY INVISIBLE (3830 2155);
FORCEPROP 1 LAST OFFPAGE TRUE
J 0
(4200 2125);
DISPLAY 0.872340 (4200 2125);
DISPLAY INVISIBLE (4200 2125);
FORCEADD OFFPAGE..2
(3875 2200);
FORCEPROP 2 LAST $XR0 209 
J 0
(4064 2200);
DISPLAY 0.638298 (4064 2200);
PAINT MONO (4064 2200);
FORCEPROP 2 LAST PATH I86
J 0
(4050 2275);
DISPLAY 1.021277 (4050 2275);
DISPLAY INVISIBLE (4050 2275);
FORCEPROP 2 LAST CDS_LIB standard
J 0
(3875 2200);
DISPLAY INVISIBLE (3875 2200);
FORCEPROP 1 LAST COMMENT_BODY TRUE
J 0
(3830 2105);
DISPLAY 0.872340 (3830 2105);
PAINT GREEN (3830 2105);
DISPLAY INVISIBLE (3830 2105);
FORCEPROP 1 LAST OFFPAGE TRUE
J 0
(4200 2075);
DISPLAY 0.872340 (4200 2075);
DISPLAY INVISIBLE (4200 2075);
FORCEADD OFFPAGE..4
R 2
(-850 3900);
FORCEPROP 2 LAST $XR0 209 
J 0
(-1132 3900);
DISPLAY 0.638298 (-1132 3900);
PAINT MONO (-1132 3900);
FORCEPROP 2 LAST CDS_LIB standard
J 0
(-850 3900);
PAINT MONO (-850 3900);
DISPLAY INVISIBLE (-850 3900);
FORCEPROP 2 LAST PATH I87
J 0
(-800 3975);
DISPLAY 1.021277 (-800 3975);
DISPLAY INVISIBLE (-800 3975);
FORCEPROP 1 LAST COMMENT_BODY TRUE
J 2
(-825 3800);
DISPLAY 0.872340 (-825 3800);
PAINT GREEN (-825 3800);
DISPLAY INVISIBLE (-825 3800);
FORCEPROP 1 LAST OFFPAGE TRUE
J 2
(-1175 3775);
DISPLAY 0.872340 (-1175 3775);
DISPLAY INVISIBLE (-1175 3775);
FORCEADD OFFPAGE..4
R 2
(-850 3950);
FORCEPROP 2 LAST $XR0 209 
J 0
(-1132 3950);
DISPLAY 0.638298 (-1132 3950);
PAINT MONO (-1132 3950);
FORCEPROP 2 LAST CDS_LIB standard
J 0
(-850 3950);
PAINT MONO (-850 3950);
DISPLAY INVISIBLE (-850 3950);
FORCEPROP 2 LAST PATH I88
J 0
(-800 4025);
DISPLAY 1.021277 (-800 4025);
DISPLAY INVISIBLE (-800 4025);
FORCEPROP 1 LAST OFFPAGE TRUE
J 2
(-1175 3825);
DISPLAY 0.872340 (-1175 3825);
DISPLAY INVISIBLE (-1175 3825);
FORCEPROP 1 LAST COMMENT_BODY TRUE
J 2
(-825 3850);
DISPLAY 0.872340 (-825 3850);
PAINT GREEN (-825 3850);
DISPLAY INVISIBLE (-825 3850);
FORCEADD Q_CAP..1
R 2
(-800 2950);
FORCEPROP 1 LAST PART_NUMBER CH4104K1B00
J 2
(-850 2800);
DISPLAY 0.510638 (-850 2800);
DISPLAY INVISIBLE (-850 2800);
FORCEPROP 1 LAST VALUE 0.1UF
J 2
(-850 3000);
DISPLAY 0.510638 (-850 3000);
FORCEPROP 1 LAST PACK_TYPE 0402
J 2
(-850 2750);
DISPLAY 0.510638 (-850 2750);
FORCEPROP 1 LAST TOLERANCE 10%
J 2
(-850 2900);
DISPLAY 0.510638 (-850 2900);
FORCEPROP 1 LAST MATERIAL X7R
J 2
(-850 2850);
DISPLAY 0.510638 (-850 2850);
FORCEPROP 1 LAST VOLTAGE 25V
J 2
(-850 2950);
DISPLAY 0.510638 (-850 2950);
FORCEPROP 1 LAST $LOCATION C609
J 2
(-850 3050);
DISPLAY 0.978723 (-850 3050);
FORCEPROP 1 LASTPIN (-800 3050) $PN 1
J 2
(-810 3030);
DISPLAY 0.787234 (-810 3030);
FORCEPROP 1 LASTPIN (-800 2850) $PN 2
J 2
(-810 2830);
DISPLAY 0.787234 (-810 2830);
FORCEPROP 2 LAST CDS_LIB pure_quanta
J 0
(-800 2950);
PAINT MONO (-800 2950);
DISPLAY INVISIBLE (-800 2950);
FORCEPROP 1 LAST PATH I89
J 2
(-850 3100);
DISPLAY 0.978723 (-850 3100);
PAINT WHITE (-850 3100);
DISPLAY INVISIBLE (-850 3100);
FORCEPROP 2 LAST CDS_LOCATION C609
J 0
(-850 3150);
DISPLAY 1.021277 (-850 3150);
DISPLAY INVISIBLE (-850 3150);
FORCEPROP 2 LAST $SEC 1
J 0
(-850 3150);
DISPLAY 0.680851 (-850 3150);
PAINT MONO (-850 3150);
DISPLAY INVISIBLE (-850 3150);
FORCEPROP 2 LAST CDS_SEC 1
J 0
(-850 3150);
DISPLAY 1.021277 (-850 3150);
DISPLAY INVISIBLE (-850 3150);
FORCEADD UNIVERSAL_GND..1
(1125 -1025);
FORCEPROP 3 LASTPIN (1125 -975) SIG_NAME GND\g
J 0
(1135 -965);
DISPLAY 0.659574 (1135 -965);
PAINT MONO (1135 -965);
DISPLAY INVISIBLE (1135 -965);
FORCEPROP 1 LAST HDL_POWER GND
J 1
(1150 -1100);
DISPLAY 0.872340 (1150 -1100);
PAINT GREEN (1150 -1100);
DISPLAY INVISIBLE (1150 -1100);
FORCEPROP 2 LAST CDS_LIB logical_power
J 0
(1125 -1025);
DISPLAY INVISIBLE (1125 -1025);
FORCEPROP 1 LAST PATH I9
J 0
(1200 -1025);
DISPLAY 0.872340 (1200 -1025);
PAINT AQUA (1200 -1025);
DISPLAY INVISIBLE (1200 -1025);
FORCEADD UNIVERSAL_GND..1
(-800 2700);
FORCEPROP 3 LASTPIN (-800 2750) SIG_NAME GND\g
J 0
(-790 2760);
DISPLAY 0.659574 (-790 2760);
PAINT MONO (-790 2760);
DISPLAY INVISIBLE (-790 2760);
FORCEPROP 2 LAST CDS_LIB logical_power
J 0
(-800 2700);
PAINT MONO (-800 2700);
DISPLAY INVISIBLE (-800 2700);
FORCEPROP 1 LAST PATH I90
J 0
(-725 2700);
DISPLAY 0.872340 (-725 2700);
PAINT AQUA (-725 2700);
DISPLAY INVISIBLE (-725 2700);
FORCEPROP 1 LAST HDL_POWER GND
J 1
(-775 2625);
DISPLAY 0.872340 (-775 2625);
PAINT GREEN (-775 2625);
DISPLAY INVISIBLE (-775 2625);
FORCEADD OFFPAGE..4
R 2
(-850 3650);
FORCEPROP 2 LAST $XR0 179 
J 0
(-1132 3650);
DISPLAY 0.638298 (-1132 3650);
PAINT MONO (-1132 3650);
FORCEPROP 2 LAST CDS_LIB standard
J 0
(-850 3650);
PAINT MONO (-850 3650);
DISPLAY INVISIBLE (-850 3650);
FORCEPROP 2 LAST PATH I91
J 0
(-1125 3700);
DISPLAY 1.021277 (-1125 3700);
DISPLAY INVISIBLE (-1125 3700);
FORCEPROP 1 LAST OFFPAGE TRUE
J 2
(-1175 3525);
DISPLAY 0.872340 (-1175 3525);
DISPLAY INVISIBLE (-1175 3525);
FORCEPROP 1 LAST COMMENT_BODY TRUE
J 2
(-825 3550);
DISPLAY 0.872340 (-825 3550);
PAINT GREEN (-825 3550);
DISPLAY INVISIBLE (-825 3550);
FORCEADD Q_RES..1
(-875 275);
FORCEPROP 1 LAST PART_NUMBER CS42003B902
J 0
(-1000 375);
DISPLAY 0.510638 (-1000 375);
DISPLAY INVISIBLE (-1000 375);
FORCEPROP 1 LAST MATERIAL EMPTY
J 0
(-525 275);
DISPLAY 0.404255 (-525 275);
PAINT RED (-525 275);
FORCEPROP 1 LAST VALUE 200K
J 2
(-650 275);
DISPLAY 0.404255 (-650 275);
FORCEPROP 1 LAST WATTAGE 1/10W
J 2
(-675 425);
DISPLAY 0.510638 (-675 425);
FORCEPROP 1 LAST PACK_TYPE 0603LF
J 0
(-1000 425);
DISPLAY 0.510638 (-1000 425);
FORCEPROP 1 LAST TOLERANCE 0.1%
J 0
(-625 275);
DISPLAY 0.404255 (-625 275);
FORCEPROP 1 LAST $LOCATION R1316
J 0
(-1125 275);
DISPLAY 0.510638 (-1125 275);
FORCEPROP 1 LASTPIN (-975 275) $PN 1
J 0
(-963 287);
DISPLAY 0.787234 (-963 287);
FORCEPROP 1 LASTPIN (-775 275) $PN 2
J 0
(-813 287);
DISPLAY 0.787234 (-813 287);
FORCEPROP 1 LAST PATH I92
J 0
(-925 425);
DISPLAY 0.978723 (-925 425);
PAINT WHITE (-925 425);
DISPLAY INVISIBLE (-925 425);
FORCEPROP 2 LAST CDS_LIB pure_quanta
J 0
(-875 275);
PAINT MONO (-875 275);
DISPLAY INVISIBLE (-875 275);
FORCEPROP 2 LAST CDS_LOCATION R1316
J 0
(-925 475);
DISPLAY 1.021277 (-925 475);
DISPLAY INVISIBLE (-925 475);
FORCEPROP 2 LAST $SEC 1
J 0
(-925 475);
DISPLAY 0.680851 (-925 475);
PAINT MONO (-925 475);
DISPLAY INVISIBLE (-925 475);
FORCEPROP 2 LAST CDS_SEC 1
J 0
(-925 475);
DISPLAY 1.021277 (-925 475);
DISPLAY INVISIBLE (-925 475);
FORCEADD OFFPAGE..2
(3875 3150);
FORCEPROP 2 LAST $XR0 240 
J 0
(4064 3150);
DISPLAY 0.638298 (4064 3150);
PAINT MONO (4064 3150);
FORCEPROP 1 LAST OFFPAGE TRUE
J 0
(4200 3025);
DISPLAY 0.872340 (4200 3025);
DISPLAY INVISIBLE (4200 3025);
FORCEPROP 1 LAST COMMENT_BODY TRUE
J 0
(3830 3055);
DISPLAY 0.872340 (3830 3055);
PAINT GREEN (3830 3055);
DISPLAY INVISIBLE (3830 3055);
FORCEPROP 2 LAST PATH I97
J 0
(4075 3200);
DISPLAY 1.021277 (4075 3200);
DISPLAY INVISIBLE (4075 3200);
FORCEPROP 2 LAST CDS_LIB standard
J 0
(3875 3150);
PAINT MONO (3875 3150);
DISPLAY INVISIBLE (3875 3150);
FORCEADD OFFPAGE..2
(3875 3100);
FORCEPROP 2 LAST $XR0 240 
J 0
(4064 3100);
DISPLAY 0.638298 (4064 3100);
PAINT MONO (4064 3100);
FORCEPROP 1 LAST OFFPAGE TRUE
J 0
(4200 2975);
DISPLAY 0.872340 (4200 2975);
DISPLAY INVISIBLE (4200 2975);
FORCEPROP 1 LAST COMMENT_BODY TRUE
J 0
(3830 3005);
DISPLAY 0.872340 (3830 3005);
PAINT GREEN (3830 3005);
DISPLAY INVISIBLE (3830 3005);
FORCEPROP 2 LAST PATH I98
J 0
(4075 3150);
DISPLAY 1.021277 (4075 3150);
DISPLAY INVISIBLE (4075 3150);
FORCEPROP 2 LAST CDS_LIB standard
J 0
(3875 3100);
PAINT MONO (3875 3100);
DISPLAY INVISIBLE (3875 3100);
FORCEADD OFFPAGE..2
(3875 2750);
FORCEPROP 2 LAST $XR0 179 
J 0
(4064 2750);
DISPLAY 0.638298 (4064 2750);
PAINT MONO (4064 2750);
FORCEPROP 2 LAST CDS_LIB standard
J 0
(3875 2750);
PAINT MONO (3875 2750);
DISPLAY INVISIBLE (3875 2750);
FORCEPROP 2 LAST PATH I99
J 0
(4075 2800);
DISPLAY 1.021277 (4075 2800);
DISPLAY INVISIBLE (4075 2800);
FORCEPROP 1 LAST COMMENT_BODY TRUE
J 0
(3830 2655);
DISPLAY 0.872340 (3830 2655);
PAINT GREEN (3830 2655);
DISPLAY INVISIBLE (3830 2655);
FORCEPROP 1 LAST OFFPAGE TRUE
J 0
(4200 2625);
DISPLAY 0.872340 (4200 2625);
DISPLAY INVISIBLE (4200 2625);
FORCEADD QUANTA_TITLE_BLOCK_C..1
(5825 -1525);
FORCEPROP 0 LAST CDS_CON_LAST_MODIFIED Fri Aug 25 14:02:51 2023
J 0
(3940 -1510);
PAINT MONO (3940 -1510);
DISPLAY INVISIBLE (3940 -1510);
FORCEPROP 1 LAST CUSTOM_TXT_CDS <CON_LAST_MODIFIED>
J 0
(3940 -1510);
DISPLAY 0.978723 (3940 -1510);
FORCEPROP 2 LAST CUSTOM_TXT_CDS <XR_PAGE_TITLE>
J 0
(-2065 3725);
DISPLAY 0.638298 (-2065 3725);
PAINT PINK (-2065 3725);
DISPLAY INVISIBLE (-2065 3725);
FORCEPROP 2 LAST CUSTOM_TXT_CDS <NAME_2>
J 0
(2650 -1475);
FORCEPROP 2 LAST CUSTOM_TXT_CDS 01
J 0
(5641 -1422);
DISPLAY 1.212766 (5641 -1422);
FORCEPROP 2 LAST CUSTOM_TXT_CDS 01
J 0
(5641 -1422);
DISPLAY 1.212766 (5641 -1422);
FORCEPROP 2 LAST CUSTOM_TXT_CDS <Q_REV>
J 0
(5641 -1422);
DISPLAY 1.212766 (5641 -1422);
FORCEPROP 2 LAST CUSTOM_TXT_CDS <NAME_1>
J 0
(2650 -1350);
FORCEPROP 2 LAST CUSTOM_TXT_CDS 01
J 0
(5641 -1422);
DISPLAY 1.212766 (5641 -1422);
FORCEPROP 2 LAST CUSTOM_TXT_CDS <Q_NUMBER>
J 0
(4422 -1422);
DISPLAY 1.212766 (4422 -1422);
FORCEPROP 2 LAST CUSTOM_TXT_CDS <CON_PAGE_NUM> OF <CON_TOTAL_PAGES>
J 0
(5379 -1507);
DISPLAY 0.978723 (5379 -1507);
FORCEPROP 2 LAST CUSTOM_TXT_CDS <Q_PROJ>
J 0
(3443 -1423);
DISPLAY 1.212766 (3443 -1423);
FORCEPROP 1 LAST Q_TITLE EMMITSBURG - CLK (1/10)
J 0
(-3491 -1499);
DISPLAY 1.957447 (-3491 -1499);
PAINT GREEN (-3491 -1499);
FORCEPROP 1 LAST Q_DEPT 
J 1
(2062 -1476);
DISPLAY 1.957447 (2062 -1476);
PAINT GREEN (2062 -1476);
FORCEPROP 2 LAST CDS_XR_PAGE_TITLE CR-179 : @S9S_MB_2U_LIB.S9S_MB_2U(SCH_1):PAGE179
J 0
(-2065 3725);
DISPLAY 0.638298 (-2065 3725);
PAINT PINK (-2065 3725);
DISPLAY INVISIBLE (-2065 3725);
FORCEPROP 2 LAST PAGE_BORDER TRUE
J 0
(-2065 3725);
DISPLAY 0.638298 (-2065 3725);
PAINT PINK (-2065 3725);
DISPLAY INVISIBLE (-2065 3725);
FORCEPROP 1 LAST COMMENT_BODY TRUE
J 0
(5837 -1538);
DISPLAY 0.978723 (5837 -1538);
PAINT GREEN (5837 -1538);
DISPLAY INVISIBLE (5837 -1538);
FORCEPROP 1 LAST CDS_LMAN_SYM_OUTLINE -9475,6775,100,-125
J 0
(5825 -1525);
DISPLAY 0.468085 (5825 -1525);
PAINT GREEN (5825 -1525);
DISPLAY INVISIBLE (5825 -1525);
FORCEPROP 2 LAST CDS_LIB pure_quanta
J 0
(5825 -1525);
PAINT MONO (5825 -1525);
DISPLAY INVISIBLE (5825 -1525);
FORCEADD CAD_NOTE..1
(-2300 4325);
FORCEPROP 2 LAST CDS_LIB logical_power
J 0
(-2300 4325);
PAINT MONO (-2300 4325);
DISPLAY INVISIBLE (-2300 4325);
FORCEPROP 1 LAST COMMENT_BODY TRUE
J 0
(-2275 4425);
DISPLAY 0.978723 (-2275 4425);
DISPLAY INVISIBLE (-2275 4425);
FORCEADD BOM_NOTE..1
(2875 4750);
FORCEPROP 0 LAST S1 BOM CHANGE: AJ0QV2N0T00 CHANGE TO AJ0QV5S0T01
J 0
(2725 4600);
DISPLAY 0.808511 (2725 4600);
PAINT SKYBLUE (2725 4600);
FORCEPROP 1 LAST COMMENT_BODY TRUE
J 0
(2900 4850);
DISPLAY 0.978723 (2900 4850);
DISPLAY INVISIBLE (2900 4850);
FORCEPROP 2 LAST CDS_LIB logical_power
J 0
(2875 4750);
DISPLAY INVISIBLE (2875 4750);
FORCEADD DNS..2
(-300 675);
PAINT RED (-300 675);
FORCEPROP 2 LAST CDS_LIB mstr_misc
J 0
(-300 675);
DISPLAY INVISIBLE (-300 675);
FORCEPROP 1 LAST COMMENT_BODY TRUE
J 0
(-300 675);
DISPLAY INVISIBLE (-300 675);
FORCEADD DNS..2
(-850 275);
PAINT RED (-850 275);
FORCEPROP 2 LAST CDS_LIB mstr_misc
J 0
(-850 275);
DISPLAY INVISIBLE (-850 275);
FORCEPROP 1 LAST COMMENT_BODY TRUE
J 0
(-850 275);
DISPLAY INVISIBLE (-850 275);
FORCEADD DNS..4
(-825 -475);
PAINT RED (-825 -475);
FORCEPROP 2 LAST CDS_LIB mstr_misc
J 0
(-825 -475);
DISPLAY INVISIBLE (-825 -475);
FORCEPROP 1 LAST COMMENT_BODY TRUE
R 1
J 0
(-750 -700);
DISPLAY 0.872340 (-750 -700);
PAINT GREEN (-750 -700);
DISPLAY INVISIBLE (-750 -700);
FORCEADD DNS..2
(-375 -800);
PAINT RED (-375 -800);
FORCEPROP 2 LAST CDS_LIB mstr_misc
J 0
(-375 -800);
DISPLAY INVISIBLE (-375 -800);
FORCEPROP 1 LAST COMMENT_BODY TRUE
J 0
(-375 -800);
DISPLAY INVISIBLE (-375 -800);
FORCEADD DNS..2
(-1300 -800);
PAINT RED (-1300 -800);
FORCEPROP 2 LAST CDS_LIB mstr_misc
J 0
(-1300 -800);
DISPLAY INVISIBLE (-1300 -800);
FORCEPROP 1 LAST COMMENT_BODY TRUE
J 0
(-1300 -800);
DISPLAY INVISIBLE (-1300 -800);
WIRE 16 -1 (-800 2850)(-800 2750);
WIRE 16 -1 (-1775 3750)(-1775 3650);
WIRE 16 -1 (2275 -875)(2275 -975);
WIRE 16 -1 (1125 -875)(1125 -975);
WIRE 16 -1 (-375 -925)(-375 -975);
WIRE 16 -1 (-500 -925)(-375 -925);
WIRE 16 -1 (-375 -875)(-375 -925);
WIRE 16 -1 (-1300 -925)(-1300 -975);
WIRE 16 -1 (-1150 -925)(-1300 -925);
WIRE 16 -1 (-1300 -875)(-1300 -925);
WIRE 16 -1 (1250 1150)(-25 1150);
FORCEPROP 0 LAST CDS_PHYS_NET_NAME CLK_100M_GPU_2_R_DN
J 0
(140 1192);
PAINT MONO (140 1192);
DISPLAY INVISIBLE (140 1192);
FORCEPROP 2 LAST SIG_NAME CLK_100M_PE_M2_0_R_DN
J 0
(165 1160);
DISPLAY 0.680851 (165 1160);
PAINT WHITE (165 1160);
WIRE 16 -1 (1450 1675)(3150 1675);
FORCEPROP 0 LAST CDS_PHYS_NET_NAME CLK_100M_GPU_1_DP
J 0
(2140 1717);
PAINT MONO (2140 1717);
DISPLAY INVISIBLE (2140 1717);
FORCEPROP 2 LAST SIG_NAME CLK_100M_E1S_0_DP
J 0
(2165 1685);
DISPLAY 0.680851 (2165 1685);
PAINT WHITE (2165 1685);
WIRE 16 -1 (1450 1525)(3150 1525);
FORCEPROP 0 LAST CDS_PHYS_NET_NAME CLK_100M_GPU_1_DN
J 0
(2140 1567);
PAINT MONO (2140 1567);
DISPLAY INVISIBLE (2140 1567);
FORCEPROP 2 LAST SIG_NAME CLK_100M_E1S_0_DN
J 0
(2165 1535);
DISPLAY 0.680851 (2165 1535);
PAINT WHITE (2165 1535);
WIRE 16 -1 (525 3250)(-800 3250);
FORCEPROP 2 LAST SIG_NAME RTC_EXT_CAP
J 0
(-775 3260);
DISPLAY 0.680851 (-775 3260);
PAINT WHITE (-775 3260);
WIRE 16 -1 (-800 3050)(-800 3250);
WIRE 16 -1 (1250 1675)(-25 1675);
FORCEPROP 0 LAST CDS_PHYS_NET_NAME CLK_100M_GPU_1_R_DP
J 0
(140 1717);
PAINT MONO (140 1717);
DISPLAY INVISIBLE (140 1717);
FORCEPROP 2 LAST SIG_NAME CLK_100M_E1S_0_R_DP
J 0
(165 1685);
DISPLAY 0.680851 (165 1685);
PAINT WHITE (165 1685);
WIRE 16 -1 (1250 1525)(-25 1525);
FORCEPROP 0 LAST CDS_PHYS_NET_NAME CLK_100M_GPU_1_R_DN
J 0
(140 1567);
PAINT MONO (140 1567);
DISPLAY INVISIBLE (140 1567);
FORCEPROP 2 LAST SIG_NAME CLK_100M_E1S_0_R_DN
J 0
(165 1535);
DISPLAY 0.680851 (165 1535);
PAINT WHITE (165 1535);
WIRE 16 2175 (-400 1450)(3575 1450);
WIRE 16 2175 (3575 1450)(3575 1100);
WIRE 16 2175 (-400 1450)(-400 1100);
WIRE 16 2175 (-400 1100)(3575 1100);
WIRE 16 -1 (1250 1300)(-25 1300);
FORCEPROP 0 LAST CDS_PHYS_NET_NAME CLK_100M_GPU_2_R_DP
J 0
(140 1342);
PAINT MONO (140 1342);
DISPLAY INVISIBLE (140 1342);
FORCEPROP 2 LAST SIG_NAME CLK_100M_PE_M2_0_R_DP
J 0
(165 1310);
DISPLAY 0.680851 (165 1310);
PAINT WHITE (165 1310);
WIRE 16 -1 (-500 -575)(-500 -925);
WIRE 16 -1 (-550 -575)(-500 -575);
WIRE 16 -1 (-1150 -575)(-1150 -925);
WIRE 16 -1 (-1100 -575)(-1150 -575);
WIRE 16 -1 (1450 1150)(3150 1150);
FORCEPROP 0 LAST CDS_PHYS_NET_NAME CLK_100M_GPU_2_DN
J 0
(2140 1192);
PAINT MONO (2140 1192);
DISPLAY INVISIBLE (2140 1192);
FORCEPROP 2 LAST SIG_NAME CLK_100M_PE_M2_0_DN
J 0
(2165 1160);
DISPLAY 0.680851 (2165 1160);
PAINT WHITE (2165 1160);
WIRE 16 -1 (1450 1300)(3150 1300);
FORCEPROP 0 LAST CDS_PHYS_NET_NAME CLK_100M_GPU_2_DP
J 0
(2140 1342);
PAINT MONO (2140 1342);
DISPLAY INVISIBLE (2140 1342);
FORCEPROP 2 LAST SIG_NAME CLK_100M_PE_M2_0_DP
J 0
(2165 1310);
DISPLAY 0.680851 (2165 1310);
PAINT WHITE (2165 1310);
WIRE 16 -1 (2525 2350)(3825 2350);
FORCEPROP 2 LAST SIG_NAME CLK_25M_PCH_CPU0_DN
J 0
(2715 2360);
DISPLAY 0.680851 (2715 2360);
PAINT WHITE (2715 2360);
WIRE 16 -1 (3825 2600)(2525 2600);
FORCEPROP 2 LAST SIG_NAME TP_CLK_100M_PCH_1_DN
J 0
(2715 2610);
DISPLAY 0.680851 (2715 2610);
PAINT WHITE (2715 2610);
WIRE 16 -1 (3825 2700)(2525 2700);
FORCEPROP 2 LAST SIG_NAME CLK_100M_PE_M2_0_R_DN
J 0
(2715 2710);
DISPLAY 0.680851 (2715 2710);
PAINT WHITE (2715 2710);
WIRE 16 -1 (3825 2800)(2525 2800);
FORCEPROP 2 LAST SIG_NAME CLK_100M_E1S_0_R_DN
J 0
(2715 2810);
DISPLAY 0.680851 (2715 2810);
PAINT WHITE (2715 2810);
WIRE 16 -1 (3825 2900)(2525 2900);
FORCEPROP 2 LAST SIG_NAME TP_CLK_100M_PCH_4_DN
J 0
(2715 2910);
DISPLAY 0.680851 (2715 2910);
PAINT WHITE (2715 2910);
WIRE 16 -1 (3825 2650)(2525 2650);
FORCEPROP 2 LAST SIG_NAME TP_CLK_100M_PCH_1_DP
J 0
(2715 2660);
DISPLAY 0.680851 (2715 2660);
PAINT WHITE (2715 2660);
WIRE 16 -1 (2525 2200)(3825 2200);
FORCEPROP 2 LAST SIG_NAME CLK_25M_PCH_CPU1_DN
J 0
(2715 2210);
DISPLAY 0.680851 (2715 2210);
PAINT WHITE (2715 2210);
WIRE 16 -1 (2525 2250)(3825 2250);
FORCEPROP 2 LAST SIG_NAME CLK_25M_PCH_CPU1_DP
J 0
(2715 2260);
DISPLAY 0.680851 (2715 2260);
PAINT WHITE (2715 2260);
WIRE 16 -1 (1125 225)(2100 225);
FORCEPROP 2 LAST SIG_NAME XTAL_PCH_RTC2_R
J 0
(1265 235);
DISPLAY 0.680851 (1265 235);
PAINT WHITE (1265 235);
WIRE 16 -1 (1575 -100)(1125 -100);
WIRE 16 -1 (1125 -100)(1125 225);
WIRE 16 -1 (1125 -475)(1125 -100);
WIRE 16 -1 (1600 -475)(1125 -475);
WIRE 16 -1 (1125 -675)(1125 -475);
WIRE 16 -1 (3825 2550)(2525 2550);
FORCEPROP 2 LAST SIG_NAME TP_CLK_100M_PCH_0_DP
J 0
(2715 2560);
DISPLAY 0.680851 (2715 2560);
PAINT WHITE (2715 2560);
WIRE 16 -1 (2525 2400)(3825 2400);
FORCEPROP 2 LAST SIG_NAME CLK_25M_PCH_CPU0_DP
J 0
(2715 2410);
DISPLAY 0.680851 (2715 2410);
PAINT WHITE (2715 2410);
WIRE 16 -1 (-225 675)(800 675);
FORCEPROP 2 LAST SIG_NAME XTAL_PCH_25M_IN
J 0
(140 685);
DISPLAY 0.680851 (140 685);
PAINT WHITE (140 685);
WIRE 16 -1 (2300 225)(3325 225);
FORCEPROP 2 LAST SIG_NAME XTAL_PCH_RTC2
J 0
(2715 235);
DISPLAY 0.680851 (2715 235);
PAINT WHITE (2715 235);
WIRE 16 -1 (-1300 675)(-425 675);
FORCEPROP 0 LAST CDS_PHYS_NET_NAME XTAL_PCH_25M_IN
J 0
(-935 717);
PAINT MONO (-935 717);
DISPLAY INVISIBLE (-935 717);
FORCEPROP 2 LAST SIG_NAME XTAL_PCH_25M_IN_R
J 0
(-1210 685);
DISPLAY 0.680851 (-1210 685);
PAINT WHITE (-1210 685);
WIRE 16 -1 (-1300 275)(-1300 675);
WIRE 16 -1 (-975 275)(-1300 275);
WIRE 16 -1 (-1100 -375)(-1300 -375);
WIRE 16 -1 (-1300 -375)(-1300 275);
WIRE 16 -1 (-1300 -675)(-1300 -375);
WIRE 16 -1 (-375 550)(800 550);
FORCEPROP 2 LAST SIG_NAME XTAL_PCH_25M_OUT
J 0
(140 560);
DISPLAY 0.680851 (140 560);
PAINT WHITE (140 560);
WIRE 16 -1 (-775 275)(-375 275);
WIRE 16 -1 (-375 275)(-375 550);
WIRE 16 -1 (-375 -675)(-375 -375);
WIRE 16 -1 (-375 -375)(-375 275);
WIRE 16 -1 (-550 -375)(-375 -375);
WIRE 16 -1 (2275 125)(3325 125);
FORCEPROP 2 LAST SIG_NAME XTAL_PCH_RTC1
J 0
(2715 135);
DISPLAY 0.680851 (2715 135);
PAINT WHITE (2715 135);
WIRE 16 -1 (1775 -100)(2275 -100);
WIRE 16 -1 (2275 -100)(2275 125);
WIRE 16 -1 (2275 -675)(2275 -475);
WIRE 16 -1 (2275 -475)(2275 -100);
WIRE 16 -1 (1800 -475)(2275 -475);
WIRE 16 -1 (3825 2850)(2525 2850);
FORCEPROP 2 LAST SIG_NAME CLK_100M_E1S_0_R_DP
J 0
(2715 2860);
DISPLAY 0.680851 (2715 2860);
PAINT WHITE (2715 2860);
WIRE 16 -1 (3825 2750)(2525 2750);
FORCEPROP 2 LAST SIG_NAME CLK_100M_PE_M2_0_R_DP
J 0
(2715 2760);
DISPLAY 0.680851 (2715 2760);
PAINT WHITE (2715 2760);
WIRE 16 -1 (3825 2500)(2525 2500);
FORCEPROP 2 LAST SIG_NAME TP_CLK_100M_PCH_0_DN
J 0
(2715 2510);
DISPLAY 0.680851 (2715 2510);
PAINT WHITE (2715 2510);
WIRE 16 -1 (3825 3000)(2525 3000);
FORCEPROP 2 LAST SIG_NAME TP_CLK_100M_PCH_5_DN
J 0
(2715 3010);
DISPLAY 0.680851 (2715 3010);
PAINT WHITE (2715 3010);
WIRE 16 -1 (3825 3100)(2525 3100);
FORCEPROP 2 LAST SIG_NAME CLK_100M_BMC_P3E_DN
J 0
(2715 3110);
DISPLAY 0.680851 (2715 3110);
PAINT WHITE (2715 3110);
WIRE 16 -1 (3825 2950)(2525 2950);
FORCEPROP 2 LAST SIG_NAME TP_CLK_100M_PCH_4_DP
J 0
(2715 2960);
DISPLAY 0.680851 (2715 2960);
PAINT WHITE (2715 2960);
WIRE 16 -1 (3825 3050)(2525 3050);
FORCEPROP 2 LAST SIG_NAME TP_CLK_100M_PCH_5_DP
J 0
(2715 3060);
DISPLAY 0.680851 (2715 3060);
PAINT WHITE (2715 3060);
WIRE 16 -1 (3825 3150)(2525 3150);
FORCEPROP 2 LAST SIG_NAME CLK_100M_BMC_P3E_DP
J 0
(2715 3160);
DISPLAY 0.680851 (2715 3160);
PAINT WHITE (2715 3160);
WIRE 16 -1 (3825 3200)(2525 3200);
FORCEPROP 2 LAST SIG_NAME TP_CLK_100M_PCH_7_DN
J 0
(2715 3210);
DISPLAY 0.680851 (2715 3210);
PAINT WHITE (2715 3210);
WIRE 16 -1 (525 4050)(-1775 4050);
FORCEPROP 2 LAST SIG_NAME PD_PCH_XCLK_BIASREF
J 0
(-775 4060);
DISPLAY 0.680851 (-775 4060);
PAINT WHITE (-775 4060);
WIRE 16 -1 (-1775 3950)(-1775 4050);
WIRE 16 -1 (525 4150)(-800 4150);
FORCEPROP 2 LAST SIG_NAME TP_PCH_RSVD<19>
J 0
(-775 4160);
DISPLAY 0.680851 (-775 4160);
PAINT WHITE (-775 4160);
WIRE 16 -1 (3825 3250)(2525 3250);
FORCEPROP 2 LAST SIG_NAME TP_CLK_100M_PCH_7_DP
J 0
(2715 3260);
DISPLAY 0.680851 (2715 3260);
PAINT WHITE (2715 3260);
WIRE 16 -1 (3825 3300)(2525 3300);
FORCEPROP 2 LAST SIG_NAME TP_CLK_100M_PCH_8_DN
J 0
(2715 3310);
DISPLAY 0.680851 (2715 3310);
PAINT WHITE (2715 3310);
WIRE 16 -1 (3825 3350)(2525 3350);
FORCEPROP 2 LAST SIG_NAME TP_CLK_100M_PCH_8_DP
J 0
(2715 3360);
DISPLAY 0.680851 (2715 3360);
PAINT WHITE (2715 3360);
WIRE 16 -1 (3825 3400)(2525 3400);
FORCEPROP 2 LAST SIG_NAME TP_CLK_100M_PCH_9_DN
J 0
(2715 3410);
DISPLAY 0.680851 (2715 3410);
PAINT WHITE (2715 3410);
WIRE 16 -1 (3825 3500)(2525 3500);
FORCEPROP 2 LAST SIG_NAME TP_CLK_100M_PCH_10_DN
J 0
(2715 3510);
DISPLAY 0.680851 (2715 3510);
PAINT WHITE (2715 3510);
WIRE 16 -1 (3825 4150)(2525 4150);
FORCEPROP 2 LAST SIG_NAME TP_CLK_100M_PCH_16_DP
J 0
(2715 4160);
DISPLAY 0.680851 (2715 4160);
PAINT WHITE (2715 4160);
WIRE 16 -1 (525 3650)(-800 3650);
FORCEPROP 2 LAST SIG_NAME XTAL_PCH_RTC1
J 0
(-775 3660);
DISPLAY 0.680851 (-775 3660);
PAINT WHITE (-775 3660);
WIRE 16 -1 (525 3750)(-800 3750);
FORCEPROP 2 LAST SIG_NAME CLK_100M_CK440_PCH_EXTCLK_DN
J 0
(-775 3760);
DISPLAY 0.680851 (-775 3760);
PAINT WHITE (-775 3760);
WIRE 16 -1 (525 3800)(-800 3800);
FORCEPROP 2 LAST SIG_NAME CLK_100M_CK440_PCH_EXTCLK_DP
J 0
(-775 3810);
DISPLAY 0.680851 (-775 3810);
PAINT WHITE (-775 3810);
WIRE 16 -1 (525 3950)(-800 3950);
FORCEPROP 2 LAST SIG_NAME CLK_25M_PCH_REF_NS_DP
J 0
(-775 3960);
DISPLAY 0.680851 (-775 3960);
PAINT WHITE (-775 3960);
WIRE 16 -1 (525 3900)(-800 3900);
FORCEPROP 2 LAST SIG_NAME CLK_25M_PCH_REF_NS_DN
J 0
(-775 3910);
DISPLAY 0.680851 (-775 3910);
PAINT WHITE (-775 3910);
WIRE 16 -1 (525 4100)(-800 4100);
FORCEPROP 2 LAST SIG_NAME TP_PCH_RSVD<18>
J 0
(-775 4110);
DISPLAY 0.680851 (-775 4110);
PAINT WHITE (-775 4110);
WIRE 16 -1 (3825 3700)(2525 3700);
FORCEPROP 2 LAST SIG_NAME TP_CLK_100M_PCH_12_DN
J 0
(2715 3710);
DISPLAY 0.680851 (2715 3710);
PAINT WHITE (2715 3710);
WIRE 16 -1 (3825 3800)(2525 3800);
FORCEPROP 2 LAST SIG_NAME TP_CLK_100M_PCH_13_DN
J 0
(2715 3810);
DISPLAY 0.680851 (2715 3810);
PAINT WHITE (2715 3810);
WIRE 16 -1 (3825 4000)(2525 4000);
FORCEPROP 2 LAST SIG_NAME TP_CLK_100M_PCH_15_DN
J 0
(2715 4010);
DISPLAY 0.680851 (2715 4010);
PAINT WHITE (2715 4010);
WIRE 16 -1 (3825 4100)(2525 4100);
FORCEPROP 2 LAST SIG_NAME TP_CLK_100M_PCH_16_DN
J 0
(2715 4110);
DISPLAY 0.680851 (2715 4110);
PAINT WHITE (2715 4110);
WIRE 16 -1 (3825 3850)(2525 3850);
FORCEPROP 2 LAST SIG_NAME TP_CLK_100M_PCH_13_DP
J 0
(2715 3860);
DISPLAY 0.680851 (2715 3860);
PAINT WHITE (2715 3860);
WIRE 16 -1 (3825 3950)(2525 3950);
FORCEPROP 2 LAST SIG_NAME TP_CLK_100M_PCH_14_DP
J 0
(2715 3960);
DISPLAY 0.680851 (2715 3960);
PAINT WHITE (2715 3960);
WIRE 16 -1 (525 3350)(-800 3350);
FORCEPROP 2 LAST SIG_NAME XTAL_PCH_25M_OUT
J 0
(-775 3360);
DISPLAY 0.680851 (-775 3360);
PAINT WHITE (-775 3360);
WIRE 16 -1 (525 3450)(-800 3450);
FORCEPROP 2 LAST SIG_NAME XTAL_PCH_25M_IN
J 0
(-775 3460);
DISPLAY 0.680851 (-775 3460);
PAINT WHITE (-775 3460);
WIRE 16 -1 (3825 3900)(2525 3900);
FORCEPROP 2 LAST SIG_NAME TP_CLK_100M_PCH_14_DN
J 0
(2715 3910);
DISPLAY 0.680851 (2715 3910);
PAINT WHITE (2715 3910);
WIRE 16 -1 (3825 4050)(2525 4050);
FORCEPROP 2 LAST SIG_NAME TP_CLK_100M_PCH_15_DP
J 0
(2715 4060);
DISPLAY 0.680851 (2715 4060);
PAINT WHITE (2715 4060);
WIRE 16 -1 (525 3550)(-800 3550);
FORCEPROP 2 LAST SIG_NAME XTAL_PCH_RTC2
J 0
(-775 3560);
DISPLAY 0.680851 (-775 3560);
PAINT WHITE (-775 3560);
WIRE 16 -1 (3825 3750)(2525 3750);
FORCEPROP 2 LAST SIG_NAME TP_CLK_100M_PCH_12_DP
J 0
(2715 3760);
DISPLAY 0.680851 (2715 3760);
PAINT WHITE (2715 3760);
WIRE 16 -1 (3825 3450)(2525 3450);
FORCEPROP 2 LAST SIG_NAME TP_CLK_100M_PCH_9_DP
J 0
(2715 3460);
DISPLAY 0.680851 (2715 3460);
PAINT WHITE (2715 3460);
WIRE 16 -1 (3825 3550)(2525 3550);
FORCEPROP 2 LAST SIG_NAME TP_CLK_100M_PCH_10_DP
J 0
(2715 3560);
DISPLAY 0.680851 (2715 3560);
PAINT WHITE (2715 3560);
WIRE 16 -1 (3825 3600)(2525 3600);
FORCEPROP 2 LAST SIG_NAME TP_CLK_100M_PCH_11_DN
J 0
(2715 3610);
DISPLAY 0.680851 (2715 3610);
PAINT WHITE (2715 3610);
WIRE 16 -1 (3825 3650)(2525 3650);
FORCEPROP 2 LAST SIG_NAME TP_CLK_100M_PCH_11_DP
J 0
(2715 3660);
DISPLAY 0.680851 (2715 3660);
PAINT WHITE (2715 3660);
DOT 1 (2275 -100);
DOT 1 (2275 -475);
DOT 1 (1125 -100);
DOT 1 (1125 -475);
DOT 1 (-375 275);
DOT 1 (-1300 275);
DOT 1 (-375 -375);
DOT 1 (-1300 -375);
DOT 1 (-375 -925);
DOT 1 (-1300 -925);
FORCENOTE
PLACE WITHIN 1.5 INCHES TO PCH
(-2450 4175) 0;
DISPLAY LEFT (-2450 4175);
DISPLAY 1.021277 (-2450 4175);
FORCENOTE
20210929 MODIFY FOR GT
(-3300 4850) 0;
DISPLAY LEFT (-3300 4850);
DISPLAY 2.510638 (-3300 4850);
PAINT PINK (-3300 4850);
FORCENOTE
20211206 ADD 0OHM
(875 1000) 0;
DISPLAY LEFT (875 1000);
DISPLAY 1.276596 (875 1000);
PAINT PINK (875 1000);
QUIT
